FILE_TYPE = MACRO_DRAWING;
SET COLOR_WIRE YELLOW;
SET COLOR_PROP MONO;
SET COLOR_DOT WHITE;
SET COLOR_ARC YELLOW;
SET COLOR_BODY GREEN;
SET COLOR_NOTE MONO;
SET PROP_DISPLAY VALUE;
SET PAGE_NUMBER P112;
FORCEADD OFFPAGE..1
(-3200 4025);
FORCEPROP 2 LAST $XR3 112 
J 0
(-3482 3989);
DISPLAY 0.638298 (-3482 3989);
PAINT MONO (-3482 3989);
FORCEPROP 2 LAST $XR2 254 
J 0
(-3722 4025);
DISPLAY 0.638298 (-3722 4025);
PAINT MONO (-3722 4025);
FORCEPROP 2 LAST $XR1 118 
J 0
(-3602 4025);
DISPLAY 0.638298 (-3602 4025);
PAINT MONO (-3602 4025);
FORCEPROP 2 LAST $XR0 111 
J 0
(-3482 4025);
DISPLAY 0.638298 (-3482 4025);
PAINT MONO (-3482 4025);
FORCEPROP 2 LAST CDS_LIB mstr_standard
J 0
(-3200 4025);
DISPLAY 2.212766 (-3200 4025);
PAINT ORANGE (-3200 4025);
DISPLAY INVISIBLE (-3200 4025);
FORCEPROP 2 LAST PATH I100
J 0
(-3450 4075);
DISPLAY 1.021277 (-3450 4075);
PAINT ORANGE (-3450 4075);
DISPLAY INVISIBLE (-3450 4075);
FORCEPROP 1 LAST OFFPAGE TRUE
J 0
(-2875 3900);
DISPLAY 1.404255 (-2875 3900);
PAINT GREEN (-2875 3900);
DISPLAY INVISIBLE (-2875 3900);
FORCEPROP 1 LAST COMMENT_BODY TRUE
J 0
(-3075 3925);
DISPLAY 1.404255 (-3075 3925);
PAINT PEACH (-3075 3925);
DISPLAY INVISIBLE (-3075 3925);
FORCEADD OFFPAGE..1
(-3200 3875);
FORCEPROP 2 LAST $XR1 111 
J 0
(-3602 3875);
DISPLAY 0.638298 (-3602 3875);
PAINT MONO (-3602 3875);
FORCEPROP 2 LAST $XR0 118 
J 0
(-3482 3875);
DISPLAY 0.638298 (-3482 3875);
PAINT MONO (-3482 3875);
FORCEPROP 2 LAST CDS_LIB mstr_standard
J 0
(-3200 3875);
DISPLAY 2.212766 (-3200 3875);
PAINT ORANGE (-3200 3875);
DISPLAY INVISIBLE (-3200 3875);
FORCEPROP 2 LAST PATH I101
J 0
(-3450 3925);
DISPLAY 1.021277 (-3450 3925);
PAINT ORANGE (-3450 3925);
DISPLAY INVISIBLE (-3450 3925);
FORCEPROP 1 LAST OFFPAGE TRUE
J 0
(-2875 3750);
DISPLAY 1.404255 (-2875 3750);
PAINT GREEN (-2875 3750);
DISPLAY INVISIBLE (-2875 3750);
FORCEPROP 1 LAST COMMENT_BODY TRUE
J 0
(-3075 3775);
DISPLAY 1.404255 (-3075 3775);
PAINT PEACH (-3075 3775);
DISPLAY INVISIBLE (-3075 3775);
FORCEADD OFFPAGE..1
(-3200 3950);
FORCEPROP 2 LAST $XR3 255 
J 0
(-3482 3914);
DISPLAY 0.638298 (-3482 3914);
PAINT MONO (-3482 3914);
FORCEPROP 2 LAST $XR2 111 
J 0
(-3722 3950);
DISPLAY 0.638298 (-3722 3950);
PAINT MONO (-3722 3950);
FORCEPROP 2 LAST $XR1 118 
J 0
(-3602 3950);
DISPLAY 0.638298 (-3602 3950);
PAINT MONO (-3602 3950);
FORCEPROP 2 LAST $XR0 112 
J 0
(-3482 3950);
DISPLAY 0.638298 (-3482 3950);
PAINT MONO (-3482 3950);
FORCEPROP 2 LAST CDS_LIB mstr_standard
J 0
(-3200 3950);
DISPLAY 2.212766 (-3200 3950);
PAINT ORANGE (-3200 3950);
DISPLAY INVISIBLE (-3200 3950);
FORCEPROP 2 LAST PATH I102
J 0
(-3450 4000);
DISPLAY 1.021277 (-3450 4000);
PAINT ORANGE (-3450 4000);
DISPLAY INVISIBLE (-3450 4000);
FORCEPROP 1 LAST OFFPAGE TRUE
J 0
(-2875 3825);
DISPLAY 1.404255 (-2875 3825);
PAINT GREEN (-2875 3825);
DISPLAY INVISIBLE (-2875 3825);
FORCEPROP 1 LAST COMMENT_BODY TRUE
J 0
(-3075 3850);
DISPLAY 1.404255 (-3075 3850);
PAINT PEACH (-3075 3850);
DISPLAY INVISIBLE (-3075 3850);
FORCEADD OFFPAGE..1
(-3200 3800);
FORCEPROP 2 LAST $XR3 112 
J 0
(-3482 3764);
DISPLAY 0.638298 (-3482 3764);
PAINT MONO (-3482 3764);
FORCEPROP 2 LAST $XR2 254 
J 0
(-3722 3800);
DISPLAY 0.638298 (-3722 3800);
PAINT MONO (-3722 3800);
FORCEPROP 2 LAST $XR1 118 
J 0
(-3602 3800);
DISPLAY 0.638298 (-3602 3800);
PAINT MONO (-3602 3800);
FORCEPROP 2 LAST $XR0 111 
J 0
(-3482 3800);
DISPLAY 0.638298 (-3482 3800);
PAINT MONO (-3482 3800);
FORCEPROP 2 LAST CDS_LIB mstr_standard
J 0
(-3200 3800);
DISPLAY 2.212766 (-3200 3800);
PAINT ORANGE (-3200 3800);
DISPLAY INVISIBLE (-3200 3800);
FORCEPROP 2 LAST PATH I103
J 0
(-3450 3850);
DISPLAY 1.021277 (-3450 3850);
PAINT ORANGE (-3450 3850);
DISPLAY INVISIBLE (-3450 3850);
FORCEPROP 1 LAST OFFPAGE TRUE
J 0
(-2875 3675);
DISPLAY 1.404255 (-2875 3675);
PAINT GREEN (-2875 3675);
DISPLAY INVISIBLE (-2875 3675);
FORCEPROP 1 LAST COMMENT_BODY TRUE
J 0
(-3075 3700);
DISPLAY 1.404255 (-3075 3700);
PAINT PEACH (-3075 3700);
DISPLAY INVISIBLE (-3075 3700);
FORCEADD OFFPAGE..1
(-3200 3725);
FORCEPROP 2 LAST $XR2 118 
J 0
(-3722 3725);
DISPLAY 0.638298 (-3722 3725);
PAINT MONO (-3722 3725);
FORCEPROP 2 LAST $XR1 254 
J 0
(-3602 3725);
DISPLAY 0.638298 (-3602 3725);
PAINT MONO (-3602 3725);
FORCEPROP 2 LAST $XR0 111 
J 0
(-3482 3725);
DISPLAY 0.638298 (-3482 3725);
PAINT MONO (-3482 3725);
FORCEPROP 2 LAST CDS_LIB mstr_standard
J 0
(-3200 3725);
DISPLAY 2.212766 (-3200 3725);
PAINT ORANGE (-3200 3725);
DISPLAY INVISIBLE (-3200 3725);
FORCEPROP 2 LAST PATH I104
J 0
(-3450 3775);
DISPLAY 1.021277 (-3450 3775);
PAINT ORANGE (-3450 3775);
DISPLAY INVISIBLE (-3450 3775);
FORCEPROP 1 LAST OFFPAGE TRUE
J 0
(-2875 3600);
DISPLAY 1.404255 (-2875 3600);
PAINT GREEN (-2875 3600);
DISPLAY INVISIBLE (-2875 3600);
FORCEPROP 1 LAST COMMENT_BODY TRUE
J 0
(-3075 3625);
DISPLAY 1.404255 (-3075 3625);
PAINT PEACH (-3075 3625);
DISPLAY INVISIBLE (-3075 3625);
FORCEADD OFFPAGE..1
(-3175 2775);
FORCEPROP 2 LAST $XR3 112 
J 0
(-3427 2739);
DISPLAY 0.638298 (-3427 2739);
PAINT MONO (-3427 2739);
FORCEPROP 2 LAST $XR2 254 
J 0
(-3667 2775);
DISPLAY 0.638298 (-3667 2775);
PAINT MONO (-3667 2775);
FORCEPROP 2 LAST $XR1 118 
J 0
(-3547 2775);
DISPLAY 0.638298 (-3547 2775);
PAINT MONO (-3547 2775);
FORCEPROP 2 LAST $XR0 111 
J 0
(-3427 2775);
DISPLAY 0.638298 (-3427 2775);
PAINT MONO (-3427 2775);
FORCEPROP 2 LAST CDS_LIB mstr_standard
J 0
(-3175 2775);
PAINT ORANGE (-3175 2775);
DISPLAY INVISIBLE (-3175 2775);
FORCEPROP 2 LAST PATH I105
J 0
(-3425 2825);
DISPLAY 1.021277 (-3425 2825);
PAINT ORANGE (-3425 2825);
DISPLAY INVISIBLE (-3425 2825);
FORCEPROP 1 LAST OFFPAGE TRUE
J 0
(-2850 2650);
DISPLAY 1.404255 (-2850 2650);
PAINT GREEN (-2850 2650);
DISPLAY INVISIBLE (-2850 2650);
FORCEPROP 1 LAST COMMENT_BODY TRUE
J 0
(-3050 2675);
DISPLAY 1.404255 (-3050 2675);
PAINT PEACH (-3050 2675);
DISPLAY INVISIBLE (-3050 2675);
FORCEADD OFFPAGE..5
(-3175 2575);
FORCEPROP 2 LAST $XR3 255 
J 0
(-3430 2539);
DISPLAY 0.638298 (-3430 2539);
PAINT MONO (-3430 2539);
FORCEPROP 2 LAST $XR2 112 
J 0
(-3670 2575);
DISPLAY 0.638298 (-3670 2575);
PAINT MONO (-3670 2575);
FORCEPROP 2 LAST $XR1 111 
J 0
(-3550 2575);
DISPLAY 0.638298 (-3550 2575);
PAINT MONO (-3550 2575);
FORCEPROP 2 LAST $XR0 118 
J 0
(-3430 2575);
DISPLAY 0.638298 (-3430 2575);
PAINT MONO (-3430 2575);
FORCEPROP 2 LAST BOM_COST DEBUG
J 2
(-3375 2675);
DISPLAY 1.617021 (-3375 2675);
PAINT WHITE (-3375 2675);
DISPLAY INVISIBLE (-3375 2675);
FORCEPROP 2 LAST ROOM CPU_JTAG_DEBUG
J 2
(-3375 2625);
DISPLAY 1.617021 (-3375 2625);
PAINT WHITE (-3375 2625);
DISPLAY INVISIBLE (-3375 2625);
FORCEPROP 2 LAST CDS_LIB mstr_standard
J 0
(-3175 2575);
PAINT ORANGE (-3175 2575);
DISPLAY INVISIBLE (-3175 2575);
FORCEPROP 2 LAST PATH I106
J 0
(-3450 2625);
DISPLAY 1.021277 (-3450 2625);
PAINT ORANGE (-3450 2625);
DISPLAY INVISIBLE (-3450 2625);
FORCEPROP 1 LAST OFFPAGE TRUE
J 0
(-2850 2450);
DISPLAY 1.404255 (-2850 2450);
PAINT GREEN (-2850 2450);
DISPLAY INVISIBLE (-2850 2450);
FORCEPROP 1 LAST COMMENT_BODY TRUE
J 0
(-3075 2500);
DISPLAY 1.404255 (-3075 2500);
PAINT PEACH (-3075 2500);
DISPLAY INVISIBLE (-3075 2500);
FORCEADD OFFPAGE..1
(-3175 2375);
FORCEPROP 2 LAST $XR3 112 
J 0
(-3427 2339);
DISPLAY 0.638298 (-3427 2339);
PAINT MONO (-3427 2339);
FORCEPROP 2 LAST $XR2 254 
J 0
(-3667 2375);
DISPLAY 0.638298 (-3667 2375);
PAINT MONO (-3667 2375);
FORCEPROP 2 LAST $XR1 118 
J 0
(-3547 2375);
DISPLAY 0.638298 (-3547 2375);
PAINT MONO (-3547 2375);
FORCEPROP 2 LAST $XR0 111 
J 0
(-3427 2375);
DISPLAY 0.638298 (-3427 2375);
PAINT MONO (-3427 2375);
FORCEPROP 2 LAST CDS_LIB mstr_standard
J 0
(-3175 2375);
PAINT ORANGE (-3175 2375);
DISPLAY INVISIBLE (-3175 2375);
FORCEPROP 2 LAST PATH I107
J 0
(-3425 2425);
DISPLAY 1.021277 (-3425 2425);
PAINT ORANGE (-3425 2425);
DISPLAY INVISIBLE (-3425 2425);
FORCEPROP 1 LAST OFFPAGE TRUE
J 0
(-2850 2250);
DISPLAY 1.404255 (-2850 2250);
PAINT GREEN (-2850 2250);
DISPLAY INVISIBLE (-2850 2250);
FORCEPROP 1 LAST COMMENT_BODY TRUE
J 0
(-3050 2275);
DISPLAY 1.404255 (-3050 2275);
PAINT PEACH (-3050 2275);
DISPLAY INVISIBLE (-3050 2275);
FORCEADD TTL3126..3
(-2200 2425);
FORCEPROP 1 LAST POWER_GROUP VCC=P3V3_STBY;GND=GND
J 0
(-2350 1900);
DISPLAY 0.617021 (-2350 1900);
PAINT ORANGE (-2350 1900);
FORCEPROP 1 LAST LOCATION U1L1
J 0
(-2350 3000);
DISPLAY 0.617021 (-2350 3000);
PAINT AQUA (-2350 3000);
FORCEPROP 1 LAST PART_NUMBER D18317-001
J 0
(-2350 1950);
DISPLAY 0.617021 (-2350 1950);
PAINT BLUE (-2350 1950);
FORCEPROP 1 LAST VALUE 74CBTLV3126
J 0
(-2350 2900);
DISPLAY 0.617021 (-2350 2900);
PAINT SKYBLUE (-2350 2900);
FORCEPROP 1 LAST MATERIAL IC
J 0
(-2350 2950);
DISPLAY 0.617021 (-2350 2950);
PAINT SKYBLUE (-2350 2950);
FORCEPROP 2 LASTPIN (-2400 2075) $PN 1
J 2
(-2410 2085);
DISPLAY 0.617021 (-2410 2085);
PAINT WHITE (-2410 2085);
FORCEPROP 2 LASTPIN (-2400 2275) $PN 4
J 2
(-2410 2285);
DISPLAY 0.617021 (-2410 2285);
PAINT WHITE (-2410 2285);
FORCEPROP 2 LASTPIN (-2400 2475) $PN 10
J 2
(-2410 2485);
DISPLAY 0.617021 (-2410 2485);
PAINT WHITE (-2410 2485);
FORCEPROP 2 LASTPIN (-2400 2675) $PN 13
J 2
(-2410 2685);
DISPLAY 0.617021 (-2410 2685);
PAINT WHITE (-2410 2685);
FORCEPROP 2 LASTPIN (-2000 2175) $PN 3
J 0
(-1990 2185);
DISPLAY 0.617021 (-1990 2185);
PAINT WHITE (-1990 2185);
FORCEPROP 2 LASTPIN (-2000 2375) $PN 6
J 0
(-1990 2385);
DISPLAY 0.617021 (-1990 2385);
PAINT WHITE (-1990 2385);
FORCEPROP 2 LASTPIN (-2000 2575) $PN 8
J 0
(-1990 2585);
DISPLAY 0.617021 (-1990 2585);
PAINT WHITE (-1990 2585);
FORCEPROP 2 LASTPIN (-2000 2775) $PN 11
J 0
(-1990 2785);
DISPLAY 0.617021 (-1990 2785);
PAINT WHITE (-1990 2785);
FORCEPROP 2 LASTPIN (-2400 2175) $PN 2
J 2
(-2410 2185);
DISPLAY 0.617021 (-2410 2185);
PAINT WHITE (-2410 2185);
FORCEPROP 2 LASTPIN (-2400 2375) $PN 5
J 2
(-2410 2385);
DISPLAY 0.617021 (-2410 2385);
PAINT WHITE (-2410 2385);
FORCEPROP 2 LASTPIN (-2400 2575) $PN 9
J 2
(-2410 2585);
DISPLAY 0.617021 (-2410 2585);
PAINT WHITE (-2410 2585);
FORCEPROP 2 LASTPIN (-2400 2775) $PN 12
J 2
(-2410 2785);
DISPLAY 0.617021 (-2410 2785);
PAINT WHITE (-2410 2785);
FORCEPROP 1 LAST PACK_TYPE QFNLF
J 0
(-2350 3050);
DISPLAY 1.595745 (-2350 3050);
PAINT SKYBLUE (-2350 3050);
DISPLAY INVISIBLE (-2350 3050);
FORCEPROP 1 LAST HAS_FIXED_SIZE 4B
J 0
(-2350 1850);
DISPLAY 1.595745 (-2350 1850);
PAINT BLUE (-2350 1850);
DISPLAY INVISIBLE (-2350 1850);
FORCEPROP 2 LAST CDS_LIB mstr_ttl
J 0
(-2200 2425);
PAINT ORANGE (-2200 2425);
DISPLAY INVISIBLE (-2200 2425);
FORCEPROP 2 LAST CDS_LOCATION U1L1
J 0
(-2350 3000);
DISPLAY 0.617021 (-2350 3000);
PAINT AQUA (-2350 3000);
DISPLAY INVISIBLE (-2350 3000);
FORCEPROP 1 LAST PATH I108
J 0
(-1900 2950);
DISPLAY 0.978723 (-1900 2950);
PAINT BLUE (-1900 2950);
DISPLAY INVISIBLE (-1900 2950);
FORCEPROP 0 LAST ROOM DEBUG
J 0
(-2350 3100);
DISPLAY 1.021277 (-2350 3100);
PAINT ORANGE (-2350 3100);
DISPLAY INVISIBLE (-2350 3100);
FORCEADD TTL3126..3
(-2200 1200);
FORCEPROP 1 LAST POWER_GROUP VCC=P3V3_STBY;GND=GND
J 0
(-2350 675);
DISPLAY 0.617021 (-2350 675);
PAINT ORANGE (-2350 675);
FORCEPROP 1 LAST LOCATION U1L5
J 0
(-2350 1775);
DISPLAY 0.617021 (-2350 1775);
PAINT AQUA (-2350 1775);
FORCEPROP 1 LAST PART_NUMBER D18317-001
J 0
(-2350 725);
DISPLAY 0.617021 (-2350 725);
PAINT BLUE (-2350 725);
FORCEPROP 1 LAST VALUE 74CBTLV3126
J 0
(-2350 1675);
DISPLAY 0.617021 (-2350 1675);
PAINT SKYBLUE (-2350 1675);
FORCEPROP 1 LAST MATERIAL IC
J 0
(-2350 1725);
DISPLAY 0.617021 (-2350 1725);
PAINT SKYBLUE (-2350 1725);
FORCEPROP 2 LASTPIN (-2400 850) $PN 1
J 2
(-2410 860);
DISPLAY 0.617021 (-2410 860);
PAINT WHITE (-2410 860);
FORCEPROP 2 LASTPIN (-2400 1050) $PN 4
J 2
(-2410 1060);
DISPLAY 0.617021 (-2410 1060);
PAINT WHITE (-2410 1060);
FORCEPROP 2 LASTPIN (-2400 1250) $PN 10
J 2
(-2410 1260);
DISPLAY 0.617021 (-2410 1260);
PAINT WHITE (-2410 1260);
FORCEPROP 2 LASTPIN (-2400 1450) $PN 13
J 2
(-2410 1460);
DISPLAY 0.617021 (-2410 1460);
PAINT WHITE (-2410 1460);
FORCEPROP 2 LASTPIN (-2000 950) $PN 3
J 0
(-1990 960);
DISPLAY 0.617021 (-1990 960);
PAINT WHITE (-1990 960);
FORCEPROP 2 LASTPIN (-2000 1150) $PN 6
J 0
(-1990 1160);
DISPLAY 0.617021 (-1990 1160);
PAINT WHITE (-1990 1160);
FORCEPROP 2 LASTPIN (-2000 1350) $PN 8
J 0
(-1990 1360);
DISPLAY 0.617021 (-1990 1360);
PAINT WHITE (-1990 1360);
FORCEPROP 2 LASTPIN (-2000 1550) $PN 11
J 0
(-1990 1560);
DISPLAY 0.617021 (-1990 1560);
PAINT WHITE (-1990 1560);
FORCEPROP 2 LASTPIN (-2400 950) $PN 2
J 2
(-2410 960);
DISPLAY 0.617021 (-2410 960);
PAINT WHITE (-2410 960);
FORCEPROP 2 LASTPIN (-2400 1150) $PN 5
J 2
(-2410 1160);
DISPLAY 0.617021 (-2410 1160);
PAINT WHITE (-2410 1160);
FORCEPROP 2 LASTPIN (-2400 1350) $PN 9
J 2
(-2410 1360);
DISPLAY 0.617021 (-2410 1360);
PAINT WHITE (-2410 1360);
FORCEPROP 2 LASTPIN (-2400 1550) $PN 12
J 2
(-2410 1560);
DISPLAY 0.617021 (-2410 1560);
PAINT WHITE (-2410 1560);
FORCEPROP 1 LAST PACK_TYPE QFNLF
J 0
(-2350 1825);
DISPLAY 1.595745 (-2350 1825);
PAINT SKYBLUE (-2350 1825);
DISPLAY INVISIBLE (-2350 1825);
FORCEPROP 2 LAST CDS_LIB mstr_ttl
J 0
(-2200 1200);
PAINT ORANGE (-2200 1200);
DISPLAY INVISIBLE (-2200 1200);
FORCEPROP 1 LAST HAS_FIXED_SIZE 4B
J 0
(-2350 625);
DISPLAY 1.595745 (-2350 625);
PAINT BLUE (-2350 625);
DISPLAY INVISIBLE (-2350 625);
FORCEPROP 2 LAST CDS_LOCATION U1L5
J 0
(-2350 1775);
DISPLAY 0.617021 (-2350 1775);
PAINT AQUA (-2350 1775);
DISPLAY INVISIBLE (-2350 1775);
FORCEPROP 1 LAST PATH I109
J 0
(-1900 1725);
DISPLAY 0.978723 (-1900 1725);
PAINT BLUE (-1900 1725);
DISPLAY INVISIBLE (-1900 1725);
FORCEPROP 0 LAST ROOM DEBUG
J 0
(-2350 1875);
DISPLAY 1.021277 (-2350 1875);
PAINT ORANGE (-2350 1875);
DISPLAY INVISIBLE (-2350 1875);
FORCEADD OFFPAGE..1
(-3175 2175);
FORCEPROP 2 LAST $XR3 112 
J 0
(-3427 2139);
DISPLAY 0.638298 (-3427 2139);
PAINT MONO (-3427 2139);
FORCEPROP 2 LAST $XR2 254 
J 0
(-3667 2175);
DISPLAY 0.638298 (-3667 2175);
PAINT MONO (-3667 2175);
FORCEPROP 2 LAST $XR1 118 
J 0
(-3547 2175);
DISPLAY 0.638298 (-3547 2175);
PAINT MONO (-3547 2175);
FORCEPROP 2 LAST $XR0 111 
J 0
(-3427 2175);
DISPLAY 0.638298 (-3427 2175);
PAINT MONO (-3427 2175);
FORCEPROP 2 LAST CDS_LIB mstr_standard
J 0
(-3175 2175);
PAINT ORANGE (-3175 2175);
DISPLAY INVISIBLE (-3175 2175);
FORCEPROP 2 LAST PATH I110
J 0
(-3425 2225);
DISPLAY 1.021277 (-3425 2225);
PAINT ORANGE (-3425 2225);
DISPLAY INVISIBLE (-3425 2225);
FORCEPROP 1 LAST OFFPAGE TRUE
J 0
(-2850 2050);
DISPLAY 1.404255 (-2850 2050);
PAINT GREEN (-2850 2050);
DISPLAY INVISIBLE (-2850 2050);
FORCEPROP 1 LAST COMMENT_BODY TRUE
J 0
(-3050 2075);
DISPLAY 1.404255 (-3050 2075);
PAINT PEACH (-3050 2075);
DISPLAY INVISIBLE (-3050 2075);
FORCEADD OFFPAGE..1
(-3175 1550);
FORCEPROP 2 LAST $XR3 112 
J 0
(-3427 1514);
DISPLAY 0.638298 (-3427 1514);
PAINT MONO (-3427 1514);
FORCEPROP 2 LAST $XR2 254 
J 0
(-3667 1550);
DISPLAY 0.638298 (-3667 1550);
PAINT MONO (-3667 1550);
FORCEPROP 2 LAST $XR1 118 
J 0
(-3547 1550);
DISPLAY 0.638298 (-3547 1550);
PAINT MONO (-3547 1550);
FORCEPROP 2 LAST $XR0 111 
J 0
(-3427 1550);
DISPLAY 0.638298 (-3427 1550);
PAINT MONO (-3427 1550);
FORCEPROP 2 LAST CDS_LIB mstr_standard
J 0
(-3175 1550);
PAINT ORANGE (-3175 1550);
DISPLAY INVISIBLE (-3175 1550);
FORCEPROP 2 LAST PATH I111
J 0
(-3425 1600);
DISPLAY 1.021277 (-3425 1600);
PAINT ORANGE (-3425 1600);
DISPLAY INVISIBLE (-3425 1600);
FORCEPROP 1 LAST OFFPAGE TRUE
J 0
(-2850 1425);
DISPLAY 1.404255 (-2850 1425);
PAINT GREEN (-2850 1425);
DISPLAY INVISIBLE (-2850 1425);
FORCEPROP 1 LAST COMMENT_BODY TRUE
J 0
(-3050 1450);
DISPLAY 1.404255 (-3050 1450);
PAINT PEACH (-3050 1450);
DISPLAY INVISIBLE (-3050 1450);
FORCEADD OFFPAGE..5
(-3175 1350);
FORCEPROP 2 LAST $XR3 255 
J 0
(-3430 1314);
DISPLAY 0.638298 (-3430 1314);
PAINT MONO (-3430 1314);
FORCEPROP 2 LAST $XR2 112 
J 0
(-3670 1350);
DISPLAY 0.638298 (-3670 1350);
PAINT MONO (-3670 1350);
FORCEPROP 2 LAST $XR1 111 
J 0
(-3550 1350);
DISPLAY 0.638298 (-3550 1350);
PAINT MONO (-3550 1350);
FORCEPROP 2 LAST $XR0 118 
J 0
(-3430 1350);
DISPLAY 0.638298 (-3430 1350);
PAINT MONO (-3430 1350);
FORCEPROP 2 LAST BOM_COST DEBUG
J 2
(-3375 1450);
DISPLAY 1.617021 (-3375 1450);
PAINT WHITE (-3375 1450);
DISPLAY INVISIBLE (-3375 1450);
FORCEPROP 2 LAST ROOM CPU_JTAG_DEBUG
J 2
(-3375 1400);
DISPLAY 1.617021 (-3375 1400);
PAINT WHITE (-3375 1400);
DISPLAY INVISIBLE (-3375 1400);
FORCEPROP 2 LAST CDS_LIB mstr_standard
J 0
(-3175 1350);
PAINT ORANGE (-3175 1350);
DISPLAY INVISIBLE (-3175 1350);
FORCEPROP 2 LAST PATH I112
J 0
(-3450 1400);
DISPLAY 1.021277 (-3450 1400);
PAINT ORANGE (-3450 1400);
DISPLAY INVISIBLE (-3450 1400);
FORCEPROP 1 LAST OFFPAGE TRUE
J 0
(-2850 1225);
DISPLAY 1.404255 (-2850 1225);
PAINT GREEN (-2850 1225);
DISPLAY INVISIBLE (-2850 1225);
FORCEPROP 1 LAST COMMENT_BODY TRUE
J 0
(-3075 1275);
DISPLAY 1.404255 (-3075 1275);
PAINT PEACH (-3075 1275);
DISPLAY INVISIBLE (-3075 1275);
FORCEADD OFFPAGE..1
(-3175 1150);
FORCEPROP 2 LAST $XR0 111 
J 0
(-3427 1150);
DISPLAY 0.638298 (-3427 1150);
PAINT MONO (-3427 1150);
FORCEPROP 2 LAST CDS_LIB mstr_standard
J 0
(-3175 1150);
PAINT ORANGE (-3175 1150);
DISPLAY INVISIBLE (-3175 1150);
FORCEPROP 2 LAST PATH I113
J 0
(-3425 1200);
DISPLAY 1.021277 (-3425 1200);
PAINT ORANGE (-3425 1200);
DISPLAY INVISIBLE (-3425 1200);
FORCEPROP 1 LAST OFFPAGE TRUE
J 0
(-2850 1025);
DISPLAY 1.404255 (-2850 1025);
PAINT GREEN (-2850 1025);
DISPLAY INVISIBLE (-2850 1025);
FORCEPROP 1 LAST COMMENT_BODY TRUE
J 0
(-3050 1050);
DISPLAY 1.404255 (-3050 1050);
PAINT PEACH (-3050 1050);
DISPLAY INVISIBLE (-3050 1050);
FORCEADD OFFPAGE..1
(-3175 950);
FORCEPROP 2 LAST $XR0 111 
J 0
(-3427 950);
DISPLAY 0.638298 (-3427 950);
PAINT MONO (-3427 950);
FORCEPROP 2 LAST CDS_LIB mstr_standard
J 0
(-3175 950);
PAINT ORANGE (-3175 950);
DISPLAY INVISIBLE (-3175 950);
FORCEPROP 2 LAST PATH I114
J 0
(-3425 1000);
DISPLAY 1.021277 (-3425 1000);
PAINT ORANGE (-3425 1000);
DISPLAY INVISIBLE (-3425 1000);
FORCEPROP 1 LAST OFFPAGE TRUE
J 0
(-2850 825);
DISPLAY 1.404255 (-2850 825);
PAINT GREEN (-2850 825);
DISPLAY INVISIBLE (-2850 825);
FORCEPROP 1 LAST COMMENT_BODY TRUE
J 0
(-3050 850);
DISPLAY 1.404255 (-3050 850);
PAINT PEACH (-3050 850);
DISPLAY INVISIBLE (-3050 850);
FORCEADD OFFPAGE..1
(-3175 850);
FORCEPROP 2 LAST $XR1 190 
J 0
(-3547 850);
DISPLAY 0.638298 (-3547 850);
PAINT MONO (-3547 850);
FORCEPROP 2 LAST $XR0 201 
J 0
(-3427 850);
DISPLAY 0.638298 (-3427 850);
PAINT MONO (-3427 850);
FORCEPROP 2 LAST CDS_LIB mstr_standard
J 0
(-3175 850);
PAINT ORANGE (-3175 850);
DISPLAY INVISIBLE (-3175 850);
FORCEPROP 2 LAST PATH I115
J 0
(-3125 925);
DISPLAY 1.021277 (-3125 925);
PAINT ORANGE (-3125 925);
DISPLAY INVISIBLE (-3125 925);
FORCEPROP 1 LAST OFFPAGE TRUE
J 0
(-2850 725);
DISPLAY 1.404255 (-2850 725);
PAINT GREEN (-2850 725);
DISPLAY INVISIBLE (-2850 725);
FORCEPROP 1 LAST COMMENT_BODY TRUE
J 0
(-3050 750);
DISPLAY 1.404255 (-3050 750);
PAINT PEACH (-3050 750);
DISPLAY INVISIBLE (-3050 750);
FORCEADD RES..2
(3500 2400);
FORCEPROP 1 LAST LOCATION R6T9
J 0
(3545 2525);
DISPLAY 0.617021 (3545 2525);
PAINT AQUA (3545 2525);
FORCEPROP 1 LAST PART_NUMBER G21796-017
J 0
(3540 2275);
DISPLAY 0.617021 (3540 2275);
PAINT BLUE (3540 2275);
FORCEPROP 1 LAST VALUE 100.0
J 0
(3545 2475);
DISPLAY 0.617021 (3545 2475);
PAINT SKYBLUE (3545 2475);
FORCEPROP 1 LAST TOLERANCE 1%
J 0
(3545 2425);
DISPLAY 0.617021 (3545 2425);
PAINT SKYBLUE (3545 2425);
FORCEPROP 1 LAST PACK_TYPE 0402
J 0
(3540 2225);
DISPLAY 0.617021 (3540 2225);
PAINT SKYBLUE (3540 2225);
FORCEPROP 1 LAST MATERIAL CHIP
J 0
(3540 2325);
DISPLAY 0.617021 (3540 2325);
PAINT SKYBLUE (3540 2325);
FORCEPROP 1 LAST WATTAGE 1/16W
J 0
(3540 2375);
DISPLAY 0.617021 (3540 2375);
PAINT SKYBLUE (3540 2375);
FORCEPROP 1 LASTPIN (3500 2300) $PN 2
J 0
(3505 2310);
DISPLAY 0.617021 (3505 2310);
PAINT ORANGE (3505 2310);
FORCEPROP 1 LASTPIN (3500 2500) $PN 1
J 0
(3505 2462);
DISPLAY 0.617021 (3505 2462);
PAINT ORANGE (3505 2462);
FORCEPROP 2 LAST SEC_TYPE 0402
J 0
(3550 2625);
DISPLAY 1.021277 (3550 2625);
PAINT ORANGE (3550 2625);
DISPLAY INVISIBLE (3550 2625);
FORCEPROP 2 LAST CDS_LIB mstr_discrete
J 0
(3500 2400);
PAINT ORANGE (3500 2400);
DISPLAY INVISIBLE (3500 2400);
FORCEPROP 2 LAST SEC 1
J 0
(3550 2625);
DISPLAY 0.680851 (3550 2625);
PAINT MONO (3550 2625);
DISPLAY INVISIBLE (3550 2625);
FORCEPROP 2 LAST CDS_LOCATION R6T9
J 0
(3545 2525);
DISPLAY 0.617021 (3545 2525);
PAINT AQUA (3545 2525);
DISPLAY INVISIBLE (3545 2525);
FORCEPROP 1 LAST PATH I120
J 0
(3550 2575);
DISPLAY 0.978723 (3550 2575);
PAINT WHITE (3550 2575);
DISPLAY INVISIBLE (3550 2575);
FORCEPROP 2 LAST ROOM DEBUG
J 0
(3545 2565);
DISPLAY 1.276596 (3545 2565);
PAINT WHITE (3545 2565);
DISPLAY INVISIBLE (3545 2565);
FORCEADD RES..2
(3175 2400);
FORCEPROP 1 LAST LOCATION R6T8
J 0
(3220 2525);
DISPLAY 0.617021 (3220 2525);
PAINT AQUA (3220 2525);
FORCEPROP 1 LAST PART_NUMBER G21796-017
J 0
(3215 2275);
DISPLAY 0.617021 (3215 2275);
PAINT BLUE (3215 2275);
FORCEPROP 1 LAST VALUE 100.0
J 0
(3220 2475);
DISPLAY 0.617021 (3220 2475);
PAINT SKYBLUE (3220 2475);
FORCEPROP 1 LAST TOLERANCE 1%
J 0
(3220 2425);
DISPLAY 0.617021 (3220 2425);
PAINT SKYBLUE (3220 2425);
FORCEPROP 1 LAST PACK_TYPE 0402
J 0
(3215 2225);
DISPLAY 0.617021 (3215 2225);
PAINT SKYBLUE (3215 2225);
FORCEPROP 1 LAST MATERIAL CHIP
J 0
(3215 2325);
DISPLAY 0.617021 (3215 2325);
PAINT SKYBLUE (3215 2325);
FORCEPROP 1 LAST WATTAGE 1/16W
J 0
(3215 2375);
DISPLAY 0.617021 (3215 2375);
PAINT SKYBLUE (3215 2375);
FORCEPROP 1 LASTPIN (3175 2300) $PN 2
J 0
(3180 2310);
DISPLAY 0.617021 (3180 2310);
PAINT ORANGE (3180 2310);
FORCEPROP 1 LASTPIN (3175 2500) $PN 1
J 0
(3180 2462);
DISPLAY 0.617021 (3180 2462);
PAINT ORANGE (3180 2462);
FORCEPROP 2 LAST SEC_TYPE 0402
J 0
(3225 2625);
DISPLAY 1.021277 (3225 2625);
PAINT ORANGE (3225 2625);
DISPLAY INVISIBLE (3225 2625);
FORCEPROP 2 LAST CDS_LIB mstr_discrete
J 0
(3175 2400);
PAINT ORANGE (3175 2400);
DISPLAY INVISIBLE (3175 2400);
FORCEPROP 2 LAST SEC 1
J 0
(3225 2625);
DISPLAY 0.680851 (3225 2625);
PAINT MONO (3225 2625);
DISPLAY INVISIBLE (3225 2625);
FORCEPROP 2 LAST CDS_LOCATION R6T8
J 0
(3220 2525);
DISPLAY 0.617021 (3220 2525);
PAINT AQUA (3220 2525);
DISPLAY INVISIBLE (3220 2525);
FORCEPROP 1 LAST PATH I121
J 0
(3225 2575);
DISPLAY 0.978723 (3225 2575);
PAINT WHITE (3225 2575);
DISPLAY INVISIBLE (3225 2575);
FORCEPROP 2 LAST ROOM DEBUG
J 0
(3220 2565);
DISPLAY 1.276596 (3220 2565);
PAINT WHITE (3220 2565);
DISPLAY INVISIBLE (3220 2565);
FORCEADD PVCCIO_CPU0..1
(3500 2700);
FORCEPROP 3 LASTPIN (3500 2650) SIG_NAME PVCCIO_CPU0\g
J 0
(3510 2660);
DISPLAY 0.659574 (3510 2660);
PAINT MONO (3510 2660);
DISPLAY INVISIBLE (3510 2660);
FORCEPROP 1 LAST VOLTAGE 1.1V
J 0
(3455 2657);
DISPLAY 0.340426 (3455 2657);
PAINT SKYBLUE (3455 2657);
DISPLAY INVISIBLE (3455 2657);
FORCEPROP 2 LAST CDS_LIB mstr_symbols
J 0
(3500 2700);
PAINT ORANGE (3500 2700);
DISPLAY INVISIBLE (3500 2700);
FORCEPROP 1 LAST PATH I122
J 0
(3550 2725);
DISPLAY 0.872340 (3550 2725);
PAINT AQUA (3550 2725);
DISPLAY INVISIBLE (3550 2725);
FORCEPROP 1 LAST BODY_TYPE PLUMBING
J 0
(3455 2657);
DISPLAY 0.340426 (3455 2657);
PAINT GREEN (3455 2657);
DISPLAY INVISIBLE (3455 2657);
FORCEPROP 1 LAST HDL_POWER PVCCIO_CPU0
J 1
(3500 2750);
DISPLAY 0.872340 (3500 2750);
PAINT GREEN (3500 2750);
DISPLAY INVISIBLE (3500 2750);
FORCEADD PVCCIO_CPU0..1
(1950 2725);
FORCEPROP 3 LASTPIN (1950 2675) SIG_NAME PVCCIO_CPU0\g
J 0
(1960 2685);
DISPLAY 0.659574 (1960 2685);
PAINT MONO (1960 2685);
DISPLAY INVISIBLE (1960 2685);
FORCEPROP 1 LAST VOLTAGE 1.1V
J 0
(1905 2682);
DISPLAY 0.340426 (1905 2682);
PAINT SKYBLUE (1905 2682);
DISPLAY INVISIBLE (1905 2682);
FORCEPROP 2 LAST CDS_LIB mstr_symbols
J 0
(1950 2725);
PAINT ORANGE (1950 2725);
DISPLAY INVISIBLE (1950 2725);
FORCEPROP 1 LAST PATH I123
J 0
(2000 2750);
DISPLAY 0.872340 (2000 2750);
PAINT AQUA (2000 2750);
DISPLAY INVISIBLE (2000 2750);
FORCEPROP 1 LAST BODY_TYPE PLUMBING
J 0
(1905 2682);
DISPLAY 0.340426 (1905 2682);
PAINT GREEN (1905 2682);
DISPLAY INVISIBLE (1905 2682);
FORCEPROP 1 LAST HDL_POWER PVCCIO_CPU0
J 1
(1950 2775);
DISPLAY 0.872340 (1950 2775);
PAINT GREEN (1950 2775);
DISPLAY INVISIBLE (1950 2775);
FORCEADD P1V05_PCH_STBY..1
(-1200 4750);
FORCEPROP 3 LASTPIN (-1200 4700) SIG_NAME P1V05_PCH_STBY\g
J 0
(-1190 4710);
DISPLAY 0.659574 (-1190 4710);
PAINT MONO (-1190 4710);
DISPLAY INVISIBLE (-1190 4710);
FORCEPROP 1 LAST VOLTAGE 1.05V
J 0
(-1245 4707);
DISPLAY 0.340426 (-1245 4707);
PAINT SKYBLUE (-1245 4707);
DISPLAY INVISIBLE (-1245 4707);
FORCEPROP 2 LAST CDS_LIB mstr_symbols
J 0
(-1200 4750);
PAINT ORANGE (-1200 4750);
DISPLAY INVISIBLE (-1200 4750);
FORCEPROP 1 LAST PATH I126
J 0
(-1150 4775);
DISPLAY 0.872340 (-1150 4775);
PAINT AQUA (-1150 4775);
DISPLAY INVISIBLE (-1150 4775);
FORCEPROP 1 LAST BODY_TYPE PLUMBING
J 0
(-1245 4707);
DISPLAY 0.340426 (-1245 4707);
PAINT GREEN (-1245 4707);
DISPLAY INVISIBLE (-1245 4707);
FORCEPROP 1 LAST HDL_POWER P1V05_PCH_STBY
J 0
(-1200 4800);
DISPLAY 0.872340 (-1200 4800);
PAINT GREEN (-1200 4800);
DISPLAY INVISIBLE (-1200 4800);
FORCEADD 74CBTLV1G125..1
(3075 3425);
FORCEPROP 1 LAST PACK_TYPE SMLF
J 0
(2900 3595);
DISPLAY 0.617021 (2900 3595);
PAINT SKYBLUE (2900 3595);
FORCEPROP 1 LAST MATERIAL IC
J 0
(2900 3645);
DISPLAY 0.617021 (2900 3645);
PAINT SKYBLUE (2900 3645);
FORCEPROP 2 LASTPIN (2825 3375) $PN 1
J 2
(2815 3385);
DISPLAY 0.617021 (2815 3385);
PAINT ORANGE (2815 3385);
FORCEPROP 2 LASTPIN (3325 3425) $PN 4
J 0
(3335 3435);
DISPLAY 0.617021 (3335 3435);
PAINT ORANGE (3335 3435);
FORCEPROP 2 LASTPIN (2825 3425) $PN 2
J 2
(2815 3435);
DISPLAY 0.617021 (2815 3435);
PAINT ORANGE (2815 3435);
FORCEPROP 1 LAST POWER_GROUP VCC=P3V3_STBY;GND=GND;
J 0
(2850 3225);
DISPLAY 0.617021 (2850 3225);
PAINT ORANGE (2850 3225);
FORCEPROP 1 LAST PART_NUMBER C88177-001
J 0
(2910 3285);
DISPLAY 0.617021 (2910 3285);
PAINT BLUE (2910 3285);
FORCEPROP 1 LAST LOCATION U1M4
J 0
(2909 3556);
DISPLAY 0.617021 (2909 3556);
PAINT AQUA (2909 3556);
FORCEPROP 2 LAST SEC_TYPE SMLF
J 0
(2900 3700);
DISPLAY 1.021277 (2900 3700);
PAINT ORANGE (2900 3700);
DISPLAY INVISIBLE (2900 3700);
FORCEPROP 2 LAST CDS_LIB mstr_ttl
J 0
(3075 3425);
PAINT ORANGE (3075 3425);
DISPLAY INVISIBLE (3075 3425);
FORCEPROP 0 LAST BOM_COST DEBUG
J 0
(2900 3750);
DISPLAY 1.021277 (2900 3750);
PAINT ORANGE (2900 3750);
DISPLAY INVISIBLE (2900 3750);
FORCEPROP 2 LAST SEC 1
J 0
(2900 3700);
DISPLAY 0.680851 (2900 3700);
PAINT MONO (2900 3700);
DISPLAY INVISIBLE (2900 3700);
FORCEPROP 1 LAST PATH I127
J 0
(3175 3545);
DISPLAY 0.872340 (3175 3545);
PAINT PINK (3175 3545);
DISPLAY INVISIBLE (3175 3545);
FORCEPROP 0 LAST ROOM DEBUG
J 0
(2900 3750);
DISPLAY 1.021277 (2900 3750);
PAINT ORANGE (2900 3750);
DISPLAY INVISIBLE (2900 3750);
FORCEADD OFFPAGE..1
(2150 3425);
FORCEPROP 2 LAST $XR1 112 
J 0
(1779 3425);
DISPLAY 0.638298 (1779 3425);
PAINT MONO (1779 3425);
FORCEPROP 2 LAST $XR0 21 
J 0
(1899 3425);
DISPLAY 0.638298 (1899 3425);
PAINT MONO (1899 3425);
FORCEPROP 2 LAST CDS_LIB mstr_standard
J 0
(2150 3425);
PAINT ORANGE (2150 3425);
DISPLAY INVISIBLE (2150 3425);
FORCEPROP 2 LAST PATH I128
J 0
(2200 3500);
DISPLAY 1.021277 (2200 3500);
PAINT ORANGE (2200 3500);
DISPLAY INVISIBLE (2200 3500);
FORCEPROP 1 LAST OFFPAGE TRUE
J 0
(2475 3300);
DISPLAY 1.404255 (2475 3300);
PAINT GREEN (2475 3300);
DISPLAY INVISIBLE (2475 3300);
FORCEPROP 1 LAST COMMENT_BODY TRUE
J 0
(2275 3325);
DISPLAY 1.404255 (2275 3325);
PAINT PEACH (2275 3325);
DISPLAY INVISIBLE (2275 3325);
FORCEADD OFFPAGE..1
(2150 3375);
FORCEPROP 2 LAST $XR4 190 
J 0
(1659 3339);
DISPLAY 0.638298 (1659 3339);
PAINT MONO (1659 3339);
FORCEPROP 2 LAST $XR3 146 
J 0
(1779 3339);
DISPLAY 0.638298 (1779 3339);
PAINT MONO (1779 3339);
FORCEPROP 2 LAST $XR2 118 
J 0
(1659 3375);
DISPLAY 0.638298 (1659 3375);
PAINT MONO (1659 3375);
FORCEPROP 2 LAST $XR1 112 
J 0
(1779 3375);
DISPLAY 0.638298 (1779 3375);
PAINT MONO (1779 3375);
FORCEPROP 2 LAST $XR0 55 
J 0
(1899 3375);
DISPLAY 0.638298 (1899 3375);
PAINT MONO (1899 3375);
FORCEPROP 2 LAST CDS_LIB mstr_standard
J 0
(2150 3375);
PAINT ORANGE (2150 3375);
DISPLAY INVISIBLE (2150 3375);
FORCEPROP 2 LAST PATH I129
J 0
(2200 3450);
DISPLAY 1.021277 (2200 3450);
PAINT ORANGE (2200 3450);
DISPLAY INVISIBLE (2200 3450);
FORCEPROP 1 LAST OFFPAGE TRUE
J 0
(2475 3250);
DISPLAY 1.404255 (2475 3250);
PAINT GREEN (2475 3250);
DISPLAY INVISIBLE (2475 3250);
FORCEPROP 1 LAST COMMENT_BODY TRUE
J 0
(2275 3275);
DISPLAY 1.404255 (2275 3275);
PAINT PEACH (2275 3275);
DISPLAY INVISIBLE (2275 3275);
FORCEADD OFFPAGE..5
R 2
(3775 3425);
FORCEPROP 2 LAST $XR1 112 
J 0
(4054 3425);
DISPLAY 0.638298 (4054 3425);
PAINT MONO (4054 3425);
FORCEPROP 2 LAST $XR0 55 
J 0
(3964 3425);
DISPLAY 0.638298 (3964 3425);
PAINT MONO (3964 3425);
FORCEPROP 2 LAST ROOM CPU_JTAG_DEBUG
J 2
(4025 3475);
DISPLAY 1.617021 (4025 3475);
PAINT WHITE (4025 3475);
DISPLAY INVISIBLE (4025 3475);
FORCEPROP 2 LAST BOM_COST DEBUG
J 2
(4025 3525);
DISPLAY 1.617021 (4025 3525);
PAINT WHITE (4025 3525);
DISPLAY INVISIBLE (4025 3525);
FORCEPROP 2 LAST CDS_LIB mstr_standard
J 0
(3775 3425);
PAINT ORANGE (3775 3425);
DISPLAY INVISIBLE (3775 3425);
FORCEPROP 2 LAST PATH I130
J 0
(3950 3500);
DISPLAY 1.021277 (3950 3500);
PAINT ORANGE (3950 3500);
DISPLAY INVISIBLE (3950 3500);
FORCEPROP 1 LAST OFFPAGE TRUE
J 2
(3450 3300);
DISPLAY 1.404255 (3450 3300);
PAINT GREEN (3450 3300);
DISPLAY INVISIBLE (3450 3300);
FORCEPROP 1 LAST COMMENT_BODY TRUE
J 2
(3675 3350);
DISPLAY 1.404255 (3675 3350);
PAINT PEACH (3675 3350);
DISPLAY INVISIBLE (3675 3350);
FORCEADD CAP_A..1
R 2
(3550 3725);
FORCEPROP 1 LAST LOCATION C1M30
J 2
(3500 3825);
DISPLAY 0.617021 (3500 3825);
PAINT AQUA (3500 3825);
FORCEPROP 1 LAST PART_NUMBER A36096-045
J 2
(3500 3575);
DISPLAY 0.617021 (3500 3575);
PAINT BLUE (3500 3575);
FORCEPROP 1 LAST VALUE 0.01UF
J 2
(3500 3775);
DISPLAY 0.617021 (3500 3775);
PAINT SKYBLUE (3500 3775);
FORCEPROP 1 LAST TOLERANCE 10%
J 2
(3500 3675);
DISPLAY 0.617021 (3500 3675);
PAINT SKYBLUE (3500 3675);
FORCEPROP 1 LAST PACK_TYPE 0402V
J 2
(3500 3525);
DISPLAY 0.617021 (3500 3525);
PAINT SKYBLUE (3500 3525);
FORCEPROP 1 LAST VOLTAGE 25V
J 2
(3500 3725);
DISPLAY 0.617021 (3500 3725);
PAINT SKYBLUE (3500 3725);
FORCEPROP 1 LAST MATERIAL X7R
J 2
(3500 3625);
DISPLAY 0.617021 (3500 3625);
PAINT SKYBLUE (3500 3625);
FORCEPROP 1 LASTPIN (3550 3825) $PN 1
J 2
(3540 3805);
DISPLAY 0.617021 (3540 3805);
PAINT ORANGE (3540 3805);
FORCEPROP 1 LASTPIN (3550 3625) $PN 2
J 2
(3540 3605);
DISPLAY 0.617021 (3540 3605);
PAINT ORANGE (3540 3605);
FORCEPROP 2 LAST BOM_COST DEBUG
J 0
(3500 3875);
DISPLAY 1.617021 (3500 3875);
PAINT WHITE (3500 3875);
DISPLAY INVISIBLE (3500 3875);
FORCEPROP 2 LAST CDS_LIB dev_discrete
J 0
(3550 3725);
PAINT ORANGE (3550 3725);
DISPLAY INVISIBLE (3550 3725);
FORCEPROP 2 LAST CDS_SEC 1
J 0
(3500 3875);
PAINT ORANGE (3500 3875);
DISPLAY INVISIBLE (3500 3875);
FORCEPROP 2 LAST SEC_TYPE 0402V
J 0
(3500 3925);
DISPLAY 1.021277 (3500 3925);
PAINT ORANGE (3500 3925);
DISPLAY INVISIBLE (3500 3925);
FORCEPROP 2 LAST SEC 1
J 0
(3500 3925);
DISPLAY 0.680851 (3500 3925);
PAINT MONO (3500 3925);
DISPLAY INVISIBLE (3500 3925);
FORCEPROP 1 LAST PATH I131
J 2
(3500 3875);
DISPLAY 0.978723 (3500 3875);
PAINT WHITE (3500 3875);
DISPLAY INVISIBLE (3500 3875);
FORCEPROP 2 LAST ROOM DEBUG
J 2
(3500 3875);
DISPLAY 1.617021 (3500 3875);
PAINT WHITE (3500 3875);
DISPLAY INVISIBLE (3500 3875);
FORCEADD GND..1
(3550 3525);
FORCEPROP 3 LASTPIN (3550 3575) SIG_NAME GND\g
J 0
(3560 3585);
DISPLAY 0.659574 (3560 3585);
PAINT MONO (3560 3585);
DISPLAY INVISIBLE (3560 3585);
FORCEPROP 1 LAST VOLTAGE 0.0V
J 0
(3505 3482);
DISPLAY 0.340426 (3505 3482);
PAINT SKYBLUE (3505 3482);
DISPLAY INVISIBLE (3505 3482);
FORCEPROP 1 LAST SIZE 1B
J 0
(3625 3475);
DISPLAY 1.893617 (3625 3475);
PAINT GREEN (3625 3475);
DISPLAY INVISIBLE (3625 3475);
FORCEPROP 2 LAST BOM_COST DEBUG
J 0
(3075 3650);
DISPLAY 1.617021 (3075 3650);
PAINT WHITE (3075 3650);
DISPLAY INVISIBLE (3075 3650);
FORCEPROP 2 LAST CDS_LIB mstr_symbols
J 0
(3550 3525);
PAINT ORANGE (3550 3525);
DISPLAY INVISIBLE (3550 3525);
FORCEPROP 1 LAST PATH I133
J 0
(3625 3525);
DISPLAY 0.872340 (3625 3525);
PAINT AQUA (3625 3525);
DISPLAY INVISIBLE (3625 3525);
FORCEPROP 2 LAST ROOM CPU_JTAG_DEBUG
J 0
(3075 3600);
DISPLAY 1.617021 (3075 3600);
PAINT WHITE (3075 3600);
DISPLAY INVISIBLE (3075 3600);
FORCEPROP 1 LAST BODY_TYPE PLUMBING
J 0
(3505 3482);
DISPLAY 0.340426 (3505 3482);
PAINT GREEN (3505 3482);
DISPLAY INVISIBLE (3505 3482);
FORCEPROP 1 LAST HDL_POWER GND
J 0
(3550 3675);
PAINT GREEN (3550 3675);
DISPLAY INVISIBLE (3550 3675);
FORCEADD PVCCIO_CPU0..1
(500 2675);
FORCEPROP 3 LASTPIN (500 2625) SIG_NAME PVCCIO_CPU0\g
J 0
(510 2635);
DISPLAY 0.659574 (510 2635);
PAINT MONO (510 2635);
DISPLAY INVISIBLE (510 2635);
FORCEPROP 1 LAST VOLTAGE 1.1V
J 0
(455 2632);
DISPLAY 0.340426 (455 2632);
PAINT SKYBLUE (455 2632);
DISPLAY INVISIBLE (455 2632);
FORCEPROP 2 LAST CDS_LIB mstr_symbols
J 0
(500 2675);
PAINT ORANGE (500 2675);
DISPLAY INVISIBLE (500 2675);
FORCEPROP 1 LAST PATH I134
J 0
(550 2700);
DISPLAY 0.872340 (550 2700);
PAINT AQUA (550 2700);
DISPLAY INVISIBLE (550 2700);
FORCEPROP 1 LAST BODY_TYPE PLUMBING
J 0
(455 2632);
DISPLAY 0.340426 (455 2632);
PAINT GREEN (455 2632);
DISPLAY INVISIBLE (455 2632);
FORCEPROP 1 LAST HDL_POWER PVCCIO_CPU0
J 1
(500 2725);
DISPLAY 0.872340 (500 2725);
PAINT GREEN (500 2725);
DISPLAY INVISIBLE (500 2725);
FORCEADD PVCCIO_CPU1..1
(1225 2675);
FORCEPROP 3 LASTPIN (1225 2625) SIG_NAME PVCCIO_CPU1\g
J 0
(1235 2635);
DISPLAY 0.659574 (1235 2635);
PAINT MONO (1235 2635);
DISPLAY INVISIBLE (1235 2635);
FORCEPROP 1 LAST VOLTAGE 1.1V
J 0
(1180 2632);
DISPLAY 0.340426 (1180 2632);
PAINT SKYBLUE (1180 2632);
DISPLAY INVISIBLE (1180 2632);
FORCEPROP 2 LAST CDS_LIB mstr_symbols
J 0
(1225 2675);
PAINT ORANGE (1225 2675);
DISPLAY INVISIBLE (1225 2675);
FORCEPROP 1 LAST PATH I135
J 0
(1275 2700);
DISPLAY 0.872340 (1275 2700);
PAINT AQUA (1275 2700);
DISPLAY INVISIBLE (1275 2700);
FORCEPROP 1 LAST BODY_TYPE PLUMBING
J 0
(1180 2632);
DISPLAY 0.340426 (1180 2632);
PAINT GREEN (1180 2632);
DISPLAY INVISIBLE (1180 2632);
FORCEPROP 1 LAST HDL_POWER PVCCIO_CPU1
J 1
(1225 2725);
DISPLAY 0.872340 (1225 2725);
PAINT GREEN (1225 2725);
DISPLAY INVISIBLE (1225 2725);
FORCEADD CAP..1
(-1125 1850);
FORCEPROP 1 LAST LOCATION C1L1
J 0
(-1075 1950);
DISPLAY 0.617021 (-1075 1950);
PAINT AQUA (-1075 1950);
FORCEPROP 1 LAST PART_NUMBER D97712-011
J 0
(-1075 1700);
DISPLAY 0.617021 (-1075 1700);
PAINT BLUE (-1075 1700);
FORCEPROP 1 LAST VALUE 1.0UF
J 0
(-1075 1900);
DISPLAY 0.617021 (-1075 1900);
PAINT SKYBLUE (-1075 1900);
FORCEPROP 1 LAST TOLERANCE 10%
J 0
(-1075 1800);
DISPLAY 0.617021 (-1075 1800);
PAINT SKYBLUE (-1075 1800);
FORCEPROP 1 LAST PACK_TYPE 0402
J 0
(-1075 1650);
DISPLAY 0.617021 (-1075 1650);
PAINT SKYBLUE (-1075 1650);
FORCEPROP 1 LAST VOLTAGE 16V
J 0
(-1075 1850);
DISPLAY 0.617021 (-1075 1850);
PAINT SKYBLUE (-1075 1850);
FORCEPROP 1 LAST MATERIAL X6S
J 0
(-1075 1750);
DISPLAY 0.617021 (-1075 1750);
PAINT SKYBLUE (-1075 1750);
FORCEPROP 1 LASTPIN (-1125 1750) $PN 2
J 0
(-1115 1730);
DISPLAY 0.617021 (-1115 1730);
PAINT ORANGE (-1115 1730);
FORCEPROP 1 LASTPIN (-1125 1950) $PN 1
J 0
(-1115 1930);
DISPLAY 0.617021 (-1115 1930);
PAINT ORANGE (-1115 1930);
FORCEPROP 2 LAST CDS_LIB mstr_discrete
J 0
(-1125 1850);
PAINT MONO (-1125 1850);
DISPLAY INVISIBLE (-1125 1850);
FORCEPROP 2 LAST SEC_TYPE 0402
J 0
(-1075 2050);
DISPLAY 1.021277 (-1075 2050);
PAINT ORANGE (-1075 2050);
DISPLAY INVISIBLE (-1075 2050);
FORCEPROP 2 LAST SEC 1
J 0
(-1075 2050);
DISPLAY 0.680851 (-1075 2050);
PAINT MONO (-1075 2050);
DISPLAY INVISIBLE (-1075 2050);
FORCEPROP 2 LAST CDS_LOCATION C1L1
J 0
(-1075 1950);
DISPLAY 0.617021 (-1075 1950);
PAINT AQUA (-1075 1950);
DISPLAY INVISIBLE (-1075 1950);
FORCEPROP 1 LAST PATH I136
J 0
(-1075 2000);
DISPLAY 0.978723 (-1075 2000);
PAINT WHITE (-1075 2000);
DISPLAY INVISIBLE (-1075 2000);
FORCEPROP 0 LAST ROOM DEBUG
J 0
(-1075 2050);
DISPLAY 1.021277 (-1075 2050);
PAINT ORANGE (-1075 2050);
DISPLAY INVISIBLE (-1075 2050);
FORCEADD GND..1
(-1125 1675);
FORCEPROP 3 LASTPIN (-1125 1725) SIG_NAME GND\g
J 0
(-1115 1735);
DISPLAY 0.659574 (-1115 1735);
PAINT MONO (-1115 1735);
DISPLAY INVISIBLE (-1115 1735);
FORCEPROP 1 LAST VOLTAGE 0.0V
J 0
(-1170 1632);
DISPLAY 0.340426 (-1170 1632);
PAINT SKYBLUE (-1170 1632);
DISPLAY INVISIBLE (-1170 1632);
FORCEPROP 2 LAST CDS_LIB mstr_symbols
J 0
(-1125 1675);
PAINT MONO (-1125 1675);
DISPLAY INVISIBLE (-1125 1675);
FORCEPROP 1 LAST SIZE 1B
J 0
(-1050 1625);
DISPLAY 2.382979 (-1050 1625);
PAINT GREEN (-1050 1625);
DISPLAY INVISIBLE (-1050 1625);
FORCEPROP 1 LAST PATH I138
J 0
(-1050 1675);
DISPLAY 0.872340 (-1050 1675);
PAINT AQUA (-1050 1675);
DISPLAY INVISIBLE (-1050 1675);
FORCEPROP 1 LAST BODY_TYPE PLUMBING
J 0
(-1170 1632);
DISPLAY 0.340426 (-1170 1632);
PAINT GREEN (-1170 1632);
DISPLAY INVISIBLE (-1170 1632);
FORCEPROP 1 LAST HDL_POWER GND
J 0
(-1125 1825);
PAINT GREEN (-1125 1825);
DISPLAY INVISIBLE (-1125 1825);
FORCEADD CAP..1
(-1350 625);
FORCEPROP 1 LAST LOCATION C1L19
J 0
(-1300 725);
DISPLAY 0.617021 (-1300 725);
PAINT AQUA (-1300 725);
FORCEPROP 1 LAST PART_NUMBER D97712-011
J 0
(-1300 475);
DISPLAY 0.617021 (-1300 475);
PAINT BLUE (-1300 475);
FORCEPROP 1 LAST VALUE 1.0UF
J 0
(-1300 675);
DISPLAY 0.617021 (-1300 675);
PAINT SKYBLUE (-1300 675);
FORCEPROP 1 LAST TOLERANCE 10%
J 0
(-1300 575);
DISPLAY 0.617021 (-1300 575);
PAINT SKYBLUE (-1300 575);
FORCEPROP 1 LAST PACK_TYPE 0402
J 0
(-1300 425);
DISPLAY 0.617021 (-1300 425);
PAINT SKYBLUE (-1300 425);
FORCEPROP 1 LAST VOLTAGE 16V
J 0
(-1300 625);
DISPLAY 0.617021 (-1300 625);
PAINT SKYBLUE (-1300 625);
FORCEPROP 1 LAST MATERIAL X6S
J 0
(-1300 525);
DISPLAY 0.617021 (-1300 525);
PAINT SKYBLUE (-1300 525);
FORCEPROP 1 LASTPIN (-1350 525) $PN 2
J 0
(-1340 505);
DISPLAY 0.617021 (-1340 505);
PAINT ORANGE (-1340 505);
FORCEPROP 1 LASTPIN (-1350 725) $PN 1
J 0
(-1340 705);
DISPLAY 0.617021 (-1340 705);
PAINT ORANGE (-1340 705);
FORCEPROP 2 LAST CDS_LIB mstr_discrete
J 0
(-1350 625);
PAINT MONO (-1350 625);
DISPLAY INVISIBLE (-1350 625);
FORCEPROP 2 LAST SEC_TYPE 0402
J 0
(-1300 825);
DISPLAY 1.021277 (-1300 825);
PAINT ORANGE (-1300 825);
DISPLAY INVISIBLE (-1300 825);
FORCEPROP 2 LAST SEC 1
J 0
(-1300 825);
DISPLAY 0.680851 (-1300 825);
PAINT MONO (-1300 825);
DISPLAY INVISIBLE (-1300 825);
FORCEPROP 2 LAST CDS_LOCATION C1L19
J 0
(-1300 725);
DISPLAY 0.617021 (-1300 725);
PAINT AQUA (-1300 725);
DISPLAY INVISIBLE (-1300 725);
FORCEPROP 1 LAST PATH I140
J 0
(-1300 775);
DISPLAY 0.978723 (-1300 775);
PAINT WHITE (-1300 775);
DISPLAY INVISIBLE (-1300 775);
FORCEPROP 0 LAST ROOM DEBUG
J 0
(-1300 825);
DISPLAY 1.021277 (-1300 825);
PAINT ORANGE (-1300 825);
DISPLAY INVISIBLE (-1300 825);
FORCEADD GND..1
(-1350 450);
FORCEPROP 3 LASTPIN (-1350 500) SIG_NAME GND\g
J 0
(-1340 510);
DISPLAY 0.659574 (-1340 510);
PAINT MONO (-1340 510);
DISPLAY INVISIBLE (-1340 510);
FORCEPROP 1 LAST VOLTAGE 0.0V
J 0
(-1395 407);
DISPLAY 0.340426 (-1395 407);
PAINT SKYBLUE (-1395 407);
DISPLAY INVISIBLE (-1395 407);
FORCEPROP 1 LAST SIZE 1B
J 0
(-1275 400);
DISPLAY 2.382979 (-1275 400);
PAINT GREEN (-1275 400);
DISPLAY INVISIBLE (-1275 400);
FORCEPROP 2 LAST CDS_LIB mstr_symbols
J 0
(-1350 450);
PAINT MONO (-1350 450);
DISPLAY INVISIBLE (-1350 450);
FORCEPROP 1 LAST PATH I141
J 0
(-1275 450);
DISPLAY 0.872340 (-1275 450);
PAINT AQUA (-1275 450);
DISPLAY INVISIBLE (-1275 450);
FORCEPROP 1 LAST BODY_TYPE PLUMBING
J 0
(-1395 407);
DISPLAY 0.340426 (-1395 407);
PAINT GREEN (-1395 407);
DISPLAY INVISIBLE (-1395 407);
FORCEPROP 1 LAST HDL_POWER GND
J 0
(-1350 600);
PAINT GREEN (-1350 600);
DISPLAY INVISIBLE (-1350 600);
FORCEADD P3V3_STBY..1
(3550 3925);
FORCEPROP 3 LASTPIN (3550 3875) SIG_NAME P3V3_STBY\g
J 0
(3560 3885);
DISPLAY 0.659574 (3560 3885);
PAINT MONO (3560 3885);
DISPLAY INVISIBLE (3560 3885);
FORCEPROP 1 LAST VOLTAGE +3.3V
J 0
(3750 4075);
DISPLAY 1.021277 (3750 4075);
PAINT SKYBLUE (3750 4075);
DISPLAY INVISIBLE (3750 4075);
FORCEPROP 2 LAST CDS_LIB mstr_symbols
J 0
(3550 3925);
PAINT ORANGE (3550 3925);
DISPLAY INVISIBLE (3550 3925);
FORCEPROP 1 LAST SIZE 1B
J 0
(3595 3947);
DISPLAY 0.340426 (3595 3947);
PAINT GREEN (3595 3947);
DISPLAY INVISIBLE (3595 3947);
FORCEPROP 1 LAST PATH I143
J 0
(3595 3927);
DISPLAY 0.340426 (3595 3927);
PAINT GREEN (3595 3927);
DISPLAY INVISIBLE (3595 3927);
FORCEPROP 1 LAST BODY_TYPE PLUMBING
J 0
(3505 3882);
DISPLAY 0.340426 (3505 3882);
PAINT GREEN (3505 3882);
DISPLAY INVISIBLE (3505 3882);
FORCEPROP 1 LAST HDL_POWER P3V3_STBY
J 0
(3250 3800);
DISPLAY 0.872340 (3250 3800);
PAINT ORANGE (3250 3800);
DISPLAY INVISIBLE (3250 3800);
FORCEADD P3V3_STBY..1
(2700 4300);
FORCEPROP 3 LASTPIN (2700 4250) SIG_NAME P3V3_STBY\g
J 0
(2710 4260);
DISPLAY 0.659574 (2710 4260);
PAINT MONO (2710 4260);
DISPLAY INVISIBLE (2710 4260);
FORCEPROP 1 LAST VOLTAGE +3.3V
J 0
(2900 4450);
DISPLAY 1.021277 (2900 4450);
PAINT SKYBLUE (2900 4450);
DISPLAY INVISIBLE (2900 4450);
FORCEPROP 1 LAST SIZE 1B
J 0
(2745 4322);
DISPLAY 0.340426 (2745 4322);
PAINT GREEN (2745 4322);
DISPLAY INVISIBLE (2745 4322);
FORCEPROP 2 LAST CDS_LIB mstr_symbols
J 0
(2700 4300);
PAINT ORANGE (2700 4300);
DISPLAY INVISIBLE (2700 4300);
FORCEPROP 1 LAST PATH I144
J 0
(2745 4302);
DISPLAY 0.340426 (2745 4302);
PAINT GREEN (2745 4302);
DISPLAY INVISIBLE (2745 4302);
FORCEPROP 1 LAST BODY_TYPE PLUMBING
J 0
(2655 4257);
DISPLAY 0.340426 (2655 4257);
PAINT GREEN (2655 4257);
DISPLAY INVISIBLE (2655 4257);
FORCEPROP 1 LAST HDL_POWER P3V3_STBY
J 0
(2400 4175);
DISPLAY 0.872340 (2400 4175);
PAINT ORANGE (2400 4175);
DISPLAY INVISIBLE (2400 4175);
FORCEADD OFFPAGE..1
R 2
(3650 4725);
FORCEPROP 2 LAST $XR1 112 
J 0
(3926 4725);
DISPLAY 0.638298 (3926 4725);
PAINT MONO (3926 4725);
FORCEPROP 2 LAST $XR0 55 
J 0
(3836 4725);
DISPLAY 0.638298 (3836 4725);
PAINT MONO (3836 4725);
FORCEPROP 2 LAST ROOM CPU_JTAG_DEBUG
J 0
(3850 4775);
DISPLAY 1.617021 (3850 4775);
PAINT WHITE (3850 4775);
DISPLAY INVISIBLE (3850 4775);
FORCEPROP 2 LAST BOM_COST DEBUG
J 0
(3850 4825);
DISPLAY 1.617021 (3850 4825);
PAINT WHITE (3850 4825);
DISPLAY INVISIBLE (3850 4825);
FORCEPROP 2 LAST CDS_LIB mstr_standard
J 0
(3650 4725);
PAINT ORANGE (3650 4725);
DISPLAY INVISIBLE (3650 4725);
FORCEPROP 2 LAST PATH I145
J 0
(3825 4800);
DISPLAY 1.021277 (3825 4800);
PAINT ORANGE (3825 4800);
DISPLAY INVISIBLE (3825 4800);
FORCEPROP 1 LAST OFFPAGE TRUE
J 2
(3325 4600);
DISPLAY 1.404255 (3325 4600);
PAINT GREEN (3325 4600);
DISPLAY INVISIBLE (3325 4600);
FORCEPROP 1 LAST COMMENT_BODY TRUE
J 2
(3525 4625);
DISPLAY 1.404255 (3525 4625);
PAINT PEACH (3525 4625);
DISPLAY INVISIBLE (3525 4625);
FORCEADD OFFPAGE..1
R 2
(3650 4625);
FORCEPROP 2 LAST $XR1 112 
J 0
(3926 4625);
DISPLAY 0.638298 (3926 4625);
PAINT MONO (3926 4625);
FORCEPROP 2 LAST $XR0 21 
J 0
(3836 4625);
DISPLAY 0.638298 (3836 4625);
PAINT MONO (3836 4625);
FORCEPROP 2 LAST ROOM CPU_JTAG_DEBUG
J 0
(3850 4675);
DISPLAY 1.617021 (3850 4675);
PAINT WHITE (3850 4675);
DISPLAY INVISIBLE (3850 4675);
FORCEPROP 2 LAST BOM_COST DEBUG
J 0
(3850 4725);
DISPLAY 1.617021 (3850 4725);
PAINT WHITE (3850 4725);
DISPLAY INVISIBLE (3850 4725);
FORCEPROP 2 LAST CDS_LIB mstr_standard
J 0
(3650 4625);
PAINT ORANGE (3650 4625);
DISPLAY INVISIBLE (3650 4625);
FORCEPROP 2 LAST PATH I146
J 0
(3825 4700);
DISPLAY 1.021277 (3825 4700);
PAINT ORANGE (3825 4700);
DISPLAY INVISIBLE (3825 4700);
FORCEPROP 1 LAST OFFPAGE TRUE
J 2
(3325 4500);
DISPLAY 1.404255 (3325 4500);
PAINT GREEN (3325 4500);
DISPLAY INVISIBLE (3325 4500);
FORCEPROP 1 LAST COMMENT_BODY TRUE
J 2
(3525 4525);
DISPLAY 1.404255 (3525 4525);
PAINT PEACH (3525 4525);
DISPLAY INVISIBLE (3525 4525);
FORCEADD PVCCIO_CPU0..1
(2675 2700);
FORCEPROP 3 LASTPIN (2675 2650) SIG_NAME PVCCIO_CPU0\g
J 0
(2685 2660);
DISPLAY 0.659574 (2685 2660);
PAINT MONO (2685 2660);
DISPLAY INVISIBLE (2685 2660);
FORCEPROP 1 LAST VOLTAGE 1.1V
J 0
(2630 2657);
DISPLAY 0.340426 (2630 2657);
PAINT SKYBLUE (2630 2657);
DISPLAY INVISIBLE (2630 2657);
FORCEPROP 2 LAST CDS_LIB mstr_symbols
J 0
(2675 2700);
PAINT ORANGE (2675 2700);
DISPLAY INVISIBLE (2675 2700);
FORCEPROP 1 LAST PATH I147
J 0
(2725 2725);
DISPLAY 0.872340 (2725 2725);
PAINT AQUA (2725 2725);
DISPLAY INVISIBLE (2725 2725);
FORCEPROP 1 LAST BODY_TYPE PLUMBING
J 0
(2630 2657);
DISPLAY 0.340426 (2630 2657);
PAINT GREEN (2630 2657);
DISPLAY INVISIBLE (2630 2657);
FORCEPROP 1 LAST HDL_POWER PVCCIO_CPU0
J 1
(2675 2750);
DISPLAY 0.872340 (2675 2750);
PAINT GREEN (2675 2750);
DISPLAY INVISIBLE (2675 2750);
FORCEADD P3V3_STBY..1
(-1125 2050);
FORCEPROP 3 LASTPIN (-1125 2000) SIG_NAME P3V3_STBY\g
J 0
(-1115 2010);
DISPLAY 0.659574 (-1115 2010);
PAINT MONO (-1115 2010);
DISPLAY INVISIBLE (-1115 2010);
FORCEPROP 1 LAST VOLTAGE +3.3V
J 0
(-925 2200);
DISPLAY 1.021277 (-925 2200);
PAINT SKYBLUE (-925 2200);
DISPLAY INVISIBLE (-925 2200);
FORCEPROP 2 LAST CDS_LIB mstr_symbols
J 0
(-1125 2050);
PAINT ORANGE (-1125 2050);
DISPLAY INVISIBLE (-1125 2050);
FORCEPROP 1 LAST SIZE 1B
J 0
(-1080 2072);
DISPLAY 0.340426 (-1080 2072);
PAINT GREEN (-1080 2072);
DISPLAY INVISIBLE (-1080 2072);
FORCEPROP 1 LAST PATH I148
J 0
(-1080 2052);
DISPLAY 0.340426 (-1080 2052);
PAINT GREEN (-1080 2052);
DISPLAY INVISIBLE (-1080 2052);
FORCEPROP 1 LAST BODY_TYPE PLUMBING
J 0
(-1170 2007);
DISPLAY 0.340426 (-1170 2007);
PAINT GREEN (-1170 2007);
DISPLAY INVISIBLE (-1170 2007);
FORCEPROP 1 LAST HDL_POWER P3V3_STBY
J 0
(-1425 1925);
DISPLAY 0.872340 (-1425 1925);
PAINT ORANGE (-1425 1925);
DISPLAY INVISIBLE (-1425 1925);
FORCEADD P3V3_STBY..1
(-1350 800);
FORCEPROP 3 LASTPIN (-1350 750) SIG_NAME P3V3_STBY\g
J 0
(-1340 760);
DISPLAY 0.659574 (-1340 760);
PAINT MONO (-1340 760);
DISPLAY INVISIBLE (-1340 760);
FORCEPROP 1 LAST VOLTAGE +3.3V
J 0
(-1150 950);
DISPLAY 1.021277 (-1150 950);
PAINT SKYBLUE (-1150 950);
DISPLAY INVISIBLE (-1150 950);
FORCEPROP 1 LAST SIZE 1B
J 0
(-1305 822);
DISPLAY 0.340426 (-1305 822);
PAINT GREEN (-1305 822);
DISPLAY INVISIBLE (-1305 822);
FORCEPROP 2 LAST CDS_LIB mstr_symbols
J 0
(-1350 800);
PAINT ORANGE (-1350 800);
DISPLAY INVISIBLE (-1350 800);
FORCEPROP 1 LAST PATH I149
J 0
(-1305 802);
DISPLAY 0.340426 (-1305 802);
PAINT GREEN (-1305 802);
DISPLAY INVISIBLE (-1305 802);
FORCEPROP 1 LAST BODY_TYPE PLUMBING
J 0
(-1395 757);
DISPLAY 0.340426 (-1395 757);
PAINT GREEN (-1395 757);
DISPLAY INVISIBLE (-1395 757);
FORCEPROP 1 LAST HDL_POWER P3V3_STBY
J 0
(-1650 675);
DISPLAY 0.872340 (-1650 675);
PAINT ORANGE (-1650 675);
DISPLAY INVISIBLE (-1650 675);
FORCEADD OFFPAGE..1
R 2
(3650 4825);
FORCEPROP 2 LAST $XR4 190 
J 0
(3956 4789);
DISPLAY 0.638298 (3956 4789);
PAINT MONO (3956 4789);
FORCEPROP 2 LAST $XR3 146 
J 0
(3836 4789);
DISPLAY 0.638298 (3836 4789);
PAINT MONO (3836 4789);
FORCEPROP 2 LAST $XR2 118 
J 0
(4046 4825);
DISPLAY 0.638298 (4046 4825);
PAINT MONO (4046 4825);
FORCEPROP 2 LAST $XR1 112 
J 0
(3926 4825);
DISPLAY 0.638298 (3926 4825);
PAINT MONO (3926 4825);
FORCEPROP 2 LAST $XR0 55 
J 0
(3836 4825);
DISPLAY 0.638298 (3836 4825);
PAINT MONO (3836 4825);
FORCEPROP 2 LAST CDS_LIB mstr_standard
J 2
(3650 4825);
DISPLAY 2.212766 (3650 4825);
PAINT ORANGE (3650 4825);
DISPLAY INVISIBLE (3650 4825);
FORCEPROP 2 LAST ROOM CPU_JTAG_DEBUG
J 0
(3850 4875);
DISPLAY 1.617021 (3850 4875);
PAINT WHITE (3850 4875);
DISPLAY INVISIBLE (3850 4875);
FORCEPROP 2 LAST BOM_COST DEBUG
J 0
(3850 4925);
DISPLAY 1.617021 (3850 4925);
PAINT WHITE (3850 4925);
DISPLAY INVISIBLE (3850 4925);
FORCEPROP 2 LAST PATH I36
J 0
(4025 4875);
DISPLAY 1.021277 (4025 4875);
PAINT ORANGE (4025 4875);
DISPLAY INVISIBLE (4025 4875);
FORCEPROP 1 LAST OFFPAGE TRUE
J 2
(3325 4700);
DISPLAY 1.404255 (3325 4700);
PAINT GREEN (3325 4700);
DISPLAY INVISIBLE (3325 4700);
FORCEPROP 1 LAST COMMENT_BODY TRUE
J 2
(3525 4725);
DISPLAY 1.404255 (3525 4725);
PAINT PEACH (3525 4725);
DISPLAY INVISIBLE (3525 4725);
FORCEADD GND..1
(2175 4450);
FORCEPROP 3 LASTPIN (2175 4500) SIG_NAME GND\g
J 0
(2185 4510);
DISPLAY 0.659574 (2185 4510);
PAINT MONO (2185 4510);
DISPLAY INVISIBLE (2185 4510);
FORCEPROP 1 LAST VOLTAGE 0.0V
J 0
(2130 4407);
DISPLAY 0.340426 (2130 4407);
PAINT SKYBLUE (2130 4407);
DISPLAY INVISIBLE (2130 4407);
FORCEPROP 2 LAST BOM_COST DEBUG
J 0
(1700 4575);
DISPLAY 1.617021 (1700 4575);
PAINT WHITE (1700 4575);
DISPLAY INVISIBLE (1700 4575);
FORCEPROP 2 LAST CDS_LIB mstr_symbols
J 0
(2175 4450);
DISPLAY 2.212766 (2175 4450);
PAINT ORANGE (2175 4450);
DISPLAY INVISIBLE (2175 4450);
FORCEPROP 1 LAST SIZE 1B
J 0
(2250 4400);
DISPLAY 1.893617 (2250 4400);
PAINT GREEN (2250 4400);
DISPLAY INVISIBLE (2250 4400);
FORCEPROP 1 LAST PATH I39
J 0
(2250 4450);
DISPLAY 0.872340 (2250 4450);
PAINT AQUA (2250 4450);
DISPLAY INVISIBLE (2250 4450);
FORCEPROP 2 LAST ROOM CPU_JTAG_DEBUG
J 0
(1700 4525);
DISPLAY 1.617021 (1700 4525);
PAINT WHITE (1700 4525);
DISPLAY INVISIBLE (1700 4525);
FORCEPROP 1 LAST BODY_TYPE PLUMBING
J 0
(2130 4407);
DISPLAY 0.340426 (2130 4407);
PAINT GREEN (2130 4407);
DISPLAY INVISIBLE (2130 4407);
FORCEPROP 1 LAST HDL_POWER GND
J 0
(2175 4600);
PAINT GREEN (2175 4600);
DISPLAY INVISIBLE (2175 4600);
FORCEADD NC7SB3157..1
R 2
(2600 4675);
FORCEPROP 2 LASTPIN (2250 4675) $PN 4
J 2
(2240 4685);
DISPLAY 0.617021 (2240 4685);
PAINT WHITE (2240 4685);
FORCEPROP 2 LASTPIN (2950 4725) $PN 3
J 0
(2960 4735);
DISPLAY 0.617021 (2960 4735);
PAINT WHITE (2960 4735);
FORCEPROP 2 LASTPIN (2950 4625) $PN 1
J 0
(2960 4635);
DISPLAY 0.617021 (2960 4635);
PAINT WHITE (2960 4635);
FORCEPROP 2 LASTPIN (2250 4525) $PN 2
J 2
(2240 4535);
DISPLAY 0.617021 (2240 4535);
PAINT WHITE (2240 4535);
FORCEPROP 2 LASTPIN (2950 4825) $PN 6
J 0
(2960 4835);
DISPLAY 0.617021 (2960 4835);
PAINT WHITE (2960 4835);
FORCEPROP 2 LASTPIN (2950 4525) $PN 5
J 0
(2960 4535);
DISPLAY 0.617021 (2960 4535);
PAINT WHITE (2960 4535);
FORCEPROP 1 LAST MATERIAL IC
J 2
(2900 4425);
DISPLAY 0.617021 (2900 4425);
PAINT SKYBLUE (2900 4425);
FORCEPROP 1 LAST PACK_TYPE SMLF
J 2
(2775 4425);
DISPLAY 0.617021 (2775 4425);
PAINT SKYBLUE (2775 4425);
FORCEPROP 1 LAST PART_NUMBER C99406-001
J 2
(2900 4900);
DISPLAY 0.617021 (2900 4900);
PAINT BLUE (2900 4900);
FORCEPROP 1 LAST LOCATION U1M7
J 2
(2900 4950);
DISPLAY 0.617021 (2900 4950);
PAINT AQUA (2900 4950);
FORCEPROP 1 LAST PATH I40
J 2
(2525 4425);
DISPLAY 0.851064 (2525 4425);
PAINT WHITE (2525 4425);
DISPLAY INVISIBLE (2525 4425);
FORCEPROP 2 LAST ROOM DEBUG
J 0
(2900 5000);
DISPLAY 1.617021 (2900 5000);
PAINT WHITE (2900 5000);
DISPLAY INVISIBLE (2900 5000);
FORCEPROP 2 LAST $SEC 1
J 0
(2900 5000);
PAINT MONO (2900 5000);
DISPLAY INVISIBLE (2900 5000);
FORCEPROP 2 LAST CDS_SEC 1
J 0
(2900 5000);
PAINT MONO (2900 5000);
DISPLAY INVISIBLE (2900 5000);
FORCEPROP 2 LAST CDS_LIB mstr_analog
J 2
(2600 4675);
DISPLAY 2.212766 (2600 4675);
PAINT ORANGE (2600 4675);
DISPLAY INVISIBLE (2600 4675);
FORCEPROP 2 LAST BOM_COST DEBUG
J 0
(2900 5050);
DISPLAY 1.617021 (2900 5050);
PAINT WHITE (2900 5050);
DISPLAY INVISIBLE (2900 5050);
FORCEADD OFFPAGE..2
R 2
(1775 4675);
FORCEPROP 2 LAST $XR0 112 
J 0
(1520 4675);
DISPLAY 0.638298 (1520 4675);
PAINT MONO (1520 4675);
FORCEPROP 2 LAST CDS_LIB mstr_standard
J 2
(1775 4675);
PAINT ORANGE (1775 4675);
DISPLAY INVISIBLE (1775 4675);
FORCEPROP 2 LAST PATH I41
J 2
(1975 4725);
DISPLAY 1.021277 (1975 4725);
PAINT ORANGE (1975 4725);
DISPLAY INVISIBLE (1975 4725);
FORCEPROP 1 LAST OFFPAGE TRUE
J 2
(1450 4550);
DISPLAY 0.872340 (1450 4550);
PAINT GREEN (1450 4550);
DISPLAY INVISIBLE (1450 4550);
FORCEPROP 1 LAST COMMENT_BODY TRUE
J 2
(1820 4580);
DISPLAY 0.872340 (1820 4580);
PAINT GREEN (1820 4580);
DISPLAY INVISIBLE (1820 4580);
FORCEADD CAP_A..1
R 2
(3100 4025);
FORCEPROP 1 LAST LOCATION C1M36
J 2
(3050 4125);
DISPLAY 0.617021 (3050 4125);
PAINT AQUA (3050 4125);
FORCEPROP 1 LAST PART_NUMBER A36096-045
J 2
(3050 3875);
DISPLAY 0.617021 (3050 3875);
PAINT BLUE (3050 3875);
FORCEPROP 1 LAST VALUE 0.01UF
J 2
(3050 4075);
DISPLAY 0.617021 (3050 4075);
PAINT SKYBLUE (3050 4075);
FORCEPROP 1 LAST TOLERANCE 10%
J 2
(3050 3975);
DISPLAY 0.617021 (3050 3975);
PAINT SKYBLUE (3050 3975);
FORCEPROP 1 LAST PACK_TYPE 0402V
J 2
(3050 3825);
DISPLAY 0.617021 (3050 3825);
PAINT SKYBLUE (3050 3825);
FORCEPROP 1 LAST VOLTAGE 25V
J 2
(3050 4025);
DISPLAY 0.617021 (3050 4025);
PAINT SKYBLUE (3050 4025);
FORCEPROP 1 LAST MATERIAL X7R
J 2
(3050 3925);
DISPLAY 0.617021 (3050 3925);
PAINT SKYBLUE (3050 3925);
FORCEPROP 1 LASTPIN (3100 4125) $PN 1
J 2
(3090 4105);
DISPLAY 0.617021 (3090 4105);
PAINT WHITE (3090 4105);
FORCEPROP 1 LASTPIN (3100 3925) $PN 2
J 2
(3090 3905);
DISPLAY 0.617021 (3090 3905);
PAINT WHITE (3090 3905);
FORCEPROP 2 LAST BOM_COST DEBUG
J 0
(3050 4175);
DISPLAY 1.617021 (3050 4175);
PAINT WHITE (3050 4175);
DISPLAY INVISIBLE (3050 4175);
FORCEPROP 2 LAST CDS_LIB dev_discrete
J 0
(3100 4025);
PAINT ORANGE (3100 4025);
DISPLAY INVISIBLE (3100 4025);
FORCEPROP 2 LAST CDS_SEC 1
J 0
(3050 4175);
PAINT ORANGE (3050 4175);
DISPLAY INVISIBLE (3050 4175);
FORCEPROP 2 LAST SEC_TYPE 0402V
J 0
(3050 4175);
DISPLAY 1.659574 (3050 4175);
PAINT ORANGE (3050 4175);
DISPLAY INVISIBLE (3050 4175);
FORCEPROP 2 LAST SEC 1
J 2
(3050 4225);
DISPLAY 1.510638 (3050 4225);
PAINT MONO (3050 4225);
DISPLAY INVISIBLE (3050 4225);
FORCEPROP 1 LAST PATH I42
J 2
(3050 4175);
DISPLAY 0.978723 (3050 4175);
PAINT WHITE (3050 4175);
DISPLAY INVISIBLE (3050 4175);
FORCEPROP 2 LAST ROOM DEBUG
J 2
(3050 4175);
DISPLAY 1.617021 (3050 4175);
PAINT WHITE (3050 4175);
DISPLAY INVISIBLE (3050 4175);
FORCEADD CAP_A..1
R 2
(2700 4025);
FORCEPROP 1 LAST PART_NUMBER D97712-004
J 2
(2650 3875);
DISPLAY 0.617021 (2650 3875);
PAINT BLUE (2650 3875);
FORCEPROP 1 LAST VALUE 1.0UF
J 2
(2650 4075);
DISPLAY 0.617021 (2650 4075);
PAINT SKYBLUE (2650 4075);
FORCEPROP 1 LAST PACK_TYPE 0402V
J 2
(2650 3825);
DISPLAY 0.617021 (2650 3825);
PAINT SKYBLUE (2650 3825);
FORCEPROP 1 LAST MATERIAL X6S
J 2
(2650 3925);
DISPLAY 0.617021 (2650 3925);
PAINT SKYBLUE (2650 3925);
FORCEPROP 1 LASTPIN (2700 4125) $PN 1
J 2
(2690 4105);
DISPLAY 0.617021 (2690 4105);
PAINT WHITE (2690 4105);
FORCEPROP 1 LASTPIN (2700 3925) $PN 2
J 2
(2690 3905);
DISPLAY 0.617021 (2690 3905);
PAINT WHITE (2690 3905);
FORCEPROP 1 LAST TOLERANCE 10%
J 2
(2650 3975);
DISPLAY 0.617021 (2650 3975);
PAINT SKYBLUE (2650 3975);
FORCEPROP 1 LAST VOLTAGE 6.3V
J 2
(2650 4025);
DISPLAY 0.617021 (2650 4025);
PAINT SKYBLUE (2650 4025);
FORCEPROP 1 LAST LOCATION C1M37
J 2
(2650 4125);
DISPLAY 0.617021 (2650 4125);
PAINT AQUA (2650 4125);
FORCEPROP 2 LAST BOM_COST DEBUG
J 0
(2650 4175);
DISPLAY 1.617021 (2650 4175);
PAINT WHITE (2650 4175);
DISPLAY INVISIBLE (2650 4175);
FORCEPROP 2 LAST CDS_LIB dev_discrete
J 0
(2700 4025);
PAINT ORANGE (2700 4025);
DISPLAY INVISIBLE (2700 4025);
FORCEPROP 2 LAST CDS_SEC 1
J 0
(2650 4225);
PAINT MONO (2650 4225);
DISPLAY INVISIBLE (2650 4225);
FORCEPROP 2 LAST $SEC 1
J 0
(2650 4225);
PAINT MONO (2650 4225);
DISPLAY INVISIBLE (2650 4225);
FORCEPROP 1 LAST PATH I47
J 2
(2650 4175);
DISPLAY 0.978723 (2650 4175);
PAINT WHITE (2650 4175);
DISPLAY INVISIBLE (2650 4175);
FORCEPROP 2 LAST ROOM DEBUG
J 2
(2650 4175);
DISPLAY 1.617021 (2650 4175);
PAINT WHITE (2650 4175);
DISPLAY INVISIBLE (2650 4175);
FORCEADD GND..1
(2700 3675);
FORCEPROP 3 LASTPIN (2700 3725) SIG_NAME GND\g
J 0
(2710 3735);
DISPLAY 0.659574 (2710 3735);
PAINT MONO (2710 3735);
DISPLAY INVISIBLE (2710 3735);
FORCEPROP 1 LAST VOLTAGE 0.0V
J 0
(2655 3632);
DISPLAY 0.340426 (2655 3632);
PAINT SKYBLUE (2655 3632);
DISPLAY INVISIBLE (2655 3632);
FORCEPROP 2 LAST BOM_COST DEBUG
J 0
(2225 3800);
DISPLAY 1.617021 (2225 3800);
PAINT WHITE (2225 3800);
DISPLAY INVISIBLE (2225 3800);
FORCEPROP 2 LAST CDS_LIB mstr_symbols
J 0
(2700 3675);
DISPLAY 2.212766 (2700 3675);
PAINT ORANGE (2700 3675);
DISPLAY INVISIBLE (2700 3675);
FORCEPROP 1 LAST SIZE 1B
J 0
(2775 3625);
DISPLAY 1.893617 (2775 3625);
PAINT GREEN (2775 3625);
DISPLAY INVISIBLE (2775 3625);
FORCEPROP 1 LAST PATH I48
J 0
(2775 3675);
DISPLAY 0.872340 (2775 3675);
PAINT AQUA (2775 3675);
DISPLAY INVISIBLE (2775 3675);
FORCEPROP 2 LAST ROOM CPU_JTAG_DEBUG
J 0
(2225 3750);
DISPLAY 1.617021 (2225 3750);
PAINT WHITE (2225 3750);
DISPLAY INVISIBLE (2225 3750);
FORCEPROP 1 LAST BODY_TYPE PLUMBING
J 0
(2655 3632);
DISPLAY 0.340426 (2655 3632);
PAINT GREEN (2655 3632);
DISPLAY INVISIBLE (2655 3632);
FORCEPROP 1 LAST HDL_POWER GND
J 0
(2700 3825);
PAINT GREEN (2700 3825);
DISPLAY INVISIBLE (2700 3825);
FORCEADD RES..2
(2675 2400);
FORCEPROP 1 LAST LOCATION R6P46
J 0
(2720 2525);
DISPLAY 0.617021 (2720 2525);
PAINT AQUA (2720 2525);
FORCEPROP 1 LAST VALUE 100.0
J 0
(2720 2475);
DISPLAY 0.617021 (2720 2475);
PAINT SKYBLUE (2720 2475);
FORCEPROP 1 LAST TOLERANCE 1%
J 0
(2720 2425);
DISPLAY 0.617021 (2720 2425);
PAINT SKYBLUE (2720 2425);
FORCEPROP 1 LAST PACK_TYPE 0402
J 0
(2715 2225);
DISPLAY 0.617021 (2715 2225);
PAINT SKYBLUE (2715 2225);
FORCEPROP 1 LAST MATERIAL CHIP
J 0
(2715 2325);
DISPLAY 0.617021 (2715 2325);
PAINT SKYBLUE (2715 2325);
FORCEPROP 1 LAST WATTAGE 1/16W
J 0
(2715 2375);
DISPLAY 0.617021 (2715 2375);
PAINT SKYBLUE (2715 2375);
FORCEPROP 1 LASTPIN (2675 2300) $PN 2
J 0
(2680 2310);
DISPLAY 0.617021 (2680 2310);
PAINT ORANGE (2680 2310);
FORCEPROP 1 LASTPIN (2675 2500) $PN 1
J 0
(2680 2462);
DISPLAY 0.617021 (2680 2462);
PAINT ORANGE (2680 2462);
FORCEPROP 1 LAST PART_NUMBER G21796-017
J 0
(2715 2275);
DISPLAY 0.617021 (2715 2275);
PAINT BLUE (2715 2275);
FORCEPROP 2 LAST CDS_LIB mstr_discrete
J 0
(2675 2400);
PAINT ORANGE (2675 2400);
DISPLAY INVISIBLE (2675 2400);
FORCEPROP 2 LAST SEC_TYPE 0402
J 0
(2725 2625);
DISPLAY 1.021277 (2725 2625);
PAINT ORANGE (2725 2625);
DISPLAY INVISIBLE (2725 2625);
FORCEPROP 2 LAST SEC 1
J 0
(2725 2625);
DISPLAY 0.680851 (2725 2625);
PAINT MONO (2725 2625);
DISPLAY INVISIBLE (2725 2625);
FORCEPROP 2 LAST CDS_LOCATION R6P46
J 0
(2720 2525);
DISPLAY 0.617021 (2720 2525);
PAINT AQUA (2720 2525);
DISPLAY INVISIBLE (2720 2525);
FORCEPROP 1 LAST PATH I49
J 0
(2725 2575);
DISPLAY 0.978723 (2725 2575);
PAINT WHITE (2725 2575);
DISPLAY INVISIBLE (2725 2575);
FORCEPROP 2 LAST ROOM DEBUG
J 0
(2720 2565);
DISPLAY 1.276596 (2720 2565);
PAINT WHITE (2720 2565);
DISPLAY INVISIBLE (2720 2565);
FORCEADD RES..2
(2325 2400);
FORCEPROP 1 LAST LOCATION R7P30
J 0
(2370 2525);
DISPLAY 0.617021 (2370 2525);
PAINT AQUA (2370 2525);
FORCEPROP 1 LAST PART_NUMBER G21796-017
J 0
(2365 2275);
DISPLAY 0.617021 (2365 2275);
PAINT BLUE (2365 2275);
FORCEPROP 1 LAST VALUE 100.0
J 0
(2370 2475);
DISPLAY 0.617021 (2370 2475);
PAINT SKYBLUE (2370 2475);
FORCEPROP 1 LAST PACK_TYPE 0402
J 0
(2365 2225);
DISPLAY 0.617021 (2365 2225);
PAINT SKYBLUE (2365 2225);
FORCEPROP 1 LAST WATTAGE 1/16W
J 0
(2365 2375);
DISPLAY 0.617021 (2365 2375);
PAINT SKYBLUE (2365 2375);
FORCEPROP 1 LASTPIN (2325 2300) $PN 2
J 0
(2330 2310);
DISPLAY 0.617021 (2330 2310);
PAINT ORANGE (2330 2310);
FORCEPROP 1 LASTPIN (2325 2500) $PN 1
J 0
(2330 2462);
DISPLAY 0.617021 (2330 2462);
PAINT ORANGE (2330 2462);
FORCEPROP 1 LAST TOLERANCE 1%
J 0
(2370 2425);
DISPLAY 0.617021 (2370 2425);
PAINT SKYBLUE (2370 2425);
FORCEPROP 1 LAST MATERIAL CHIP
J 0
(2365 2325);
DISPLAY 0.617021 (2365 2325);
PAINT SKYBLUE (2365 2325);
FORCEPROP 2 LAST CDS_LIB mstr_discrete
J 0
(2325 2400);
PAINT ORANGE (2325 2400);
DISPLAY INVISIBLE (2325 2400);
FORCEPROP 2 LAST SEC_TYPE 0402
J 0
(2375 2625);
DISPLAY 1.021277 (2375 2625);
PAINT ORANGE (2375 2625);
DISPLAY INVISIBLE (2375 2625);
FORCEPROP 2 LAST SEC 1
J 0
(2375 2625);
DISPLAY 0.680851 (2375 2625);
PAINT MONO (2375 2625);
DISPLAY INVISIBLE (2375 2625);
FORCEPROP 2 LAST CDS_LOCATION R7P30
J 0
(2370 2525);
DISPLAY 0.617021 (2370 2525);
PAINT AQUA (2370 2525);
DISPLAY INVISIBLE (2370 2525);
FORCEPROP 1 LAST PATH I50
J 0
(2375 2575);
DISPLAY 0.978723 (2375 2575);
PAINT WHITE (2375 2575);
DISPLAY INVISIBLE (2375 2575);
FORCEPROP 2 LAST ROOM DEBUG
J 0
(2370 2565);
DISPLAY 1.276596 (2370 2565);
PAINT WHITE (2370 2565);
DISPLAY INVISIBLE (2370 2565);
FORCEADD RES..2
(1950 2400);
FORCEPROP 1 LAST LOCATION R1M3
J 0
(1995 2525);
DISPLAY 0.617021 (1995 2525);
PAINT AQUA (1995 2525);
FORCEPROP 1 LAST PART_NUMBER G21796-017
J 0
(1990 2275);
DISPLAY 0.617021 (1990 2275);
PAINT BLUE (1990 2275);
FORCEPROP 1 LAST VALUE 100.0
J 0
(1995 2475);
DISPLAY 0.617021 (1995 2475);
PAINT SKYBLUE (1995 2475);
FORCEPROP 1 LAST TOLERANCE 1%
J 0
(1995 2425);
DISPLAY 0.617021 (1995 2425);
PAINT SKYBLUE (1995 2425);
FORCEPROP 1 LAST PACK_TYPE 0402
J 0
(1990 2225);
DISPLAY 0.617021 (1990 2225);
PAINT SKYBLUE (1990 2225);
FORCEPROP 1 LAST MATERIAL CHIP
J 0
(1990 2325);
DISPLAY 0.617021 (1990 2325);
PAINT SKYBLUE (1990 2325);
FORCEPROP 1 LAST WATTAGE 1/16W
J 0
(1990 2375);
DISPLAY 0.617021 (1990 2375);
PAINT SKYBLUE (1990 2375);
FORCEPROP 1 LASTPIN (1950 2300) $PN 2
J 0
(1955 2310);
DISPLAY 0.617021 (1955 2310);
PAINT ORANGE (1955 2310);
FORCEPROP 1 LASTPIN (1950 2500) $PN 1
J 0
(1955 2462);
DISPLAY 0.617021 (1955 2462);
PAINT ORANGE (1955 2462);
FORCEPROP 2 LAST CDS_LIB mstr_discrete
J 0
(1950 2400);
PAINT ORANGE (1950 2400);
DISPLAY INVISIBLE (1950 2400);
FORCEPROP 2 LAST SEC_TYPE 0402
J 0
(2000 2625);
DISPLAY 1.021277 (2000 2625);
PAINT ORANGE (2000 2625);
DISPLAY INVISIBLE (2000 2625);
FORCEPROP 2 LAST SEC 1
J 0
(2000 2625);
DISPLAY 0.680851 (2000 2625);
PAINT MONO (2000 2625);
DISPLAY INVISIBLE (2000 2625);
FORCEPROP 2 LAST CDS_LOCATION R1M3
J 0
(1995 2525);
DISPLAY 0.617021 (1995 2525);
PAINT AQUA (1995 2525);
DISPLAY INVISIBLE (1995 2525);
FORCEPROP 1 LAST PATH I51
J 0
(2000 2575);
DISPLAY 0.978723 (2000 2575);
PAINT WHITE (2000 2575);
DISPLAY INVISIBLE (2000 2575);
FORCEPROP 2 LAST ROOM DEBUG
J 0
(1995 2565);
DISPLAY 1.276596 (1995 2565);
PAINT WHITE (1995 2565);
DISPLAY INVISIBLE (1995 2565);
FORCEADD PVCCIO_CPU0..1
(1175 4150);
FORCEPROP 3 LASTPIN (1175 4100) SIG_NAME PVCCIO_CPU0\g
J 0
(1185 4110);
DISPLAY 0.659574 (1185 4110);
PAINT MONO (1185 4110);
DISPLAY INVISIBLE (1185 4110);
FORCEPROP 1 LAST VOLTAGE 1.1V
J 0
(1130 4107);
DISPLAY 0.340426 (1130 4107);
PAINT SKYBLUE (1130 4107);
DISPLAY INVISIBLE (1130 4107);
FORCEPROP 2 LAST CDS_LIB mstr_symbols
J 0
(1175 4150);
PAINT ORANGE (1175 4150);
DISPLAY INVISIBLE (1175 4150);
FORCEPROP 1 LAST PATH I52
J 0
(1225 4175);
DISPLAY 0.872340 (1225 4175);
PAINT AQUA (1225 4175);
DISPLAY INVISIBLE (1225 4175);
FORCEPROP 1 LAST BODY_TYPE PLUMBING
J 0
(1130 4107);
DISPLAY 0.340426 (1130 4107);
PAINT GREEN (1130 4107);
DISPLAY INVISIBLE (1130 4107);
FORCEPROP 1 LAST HDL_POWER PVCCIO_CPU0
J 1
(1175 4200);
DISPLAY 0.872340 (1175 4200);
PAINT GREEN (1175 4200);
DISPLAY INVISIBLE (1175 4200);
FORCEADD RES..2
(1175 3800);
FORCEPROP 1 LAST LOCATION R4P15
J 0
(1220 3925);
DISPLAY 0.617021 (1220 3925);
PAINT AQUA (1220 3925);
FORCEPROP 1 LAST PART_NUMBER G21796-017
J 0
(1215 3675);
DISPLAY 0.617021 (1215 3675);
PAINT BLUE (1215 3675);
FORCEPROP 1 LAST VALUE 100.0
J 0
(1220 3875);
DISPLAY 0.617021 (1220 3875);
PAINT SKYBLUE (1220 3875);
FORCEPROP 1 LAST TOLERANCE 1%
J 0
(1220 3825);
DISPLAY 0.617021 (1220 3825);
PAINT SKYBLUE (1220 3825);
FORCEPROP 1 LAST PACK_TYPE 0402
J 0
(1215 3625);
DISPLAY 0.617021 (1215 3625);
PAINT SKYBLUE (1215 3625);
FORCEPROP 1 LAST MATERIAL CHIP
J 0
(1215 3725);
DISPLAY 0.617021 (1215 3725);
PAINT SKYBLUE (1215 3725);
FORCEPROP 1 LAST WATTAGE 1/16W
J 0
(1215 3775);
DISPLAY 0.617021 (1215 3775);
PAINT SKYBLUE (1215 3775);
FORCEPROP 1 LASTPIN (1175 3700) $PN 2
J 0
(1180 3710);
DISPLAY 0.617021 (1180 3710);
PAINT ORANGE (1180 3710);
FORCEPROP 1 LASTPIN (1175 3900) $PN 1
J 0
(1180 3862);
DISPLAY 0.617021 (1180 3862);
PAINT ORANGE (1180 3862);
FORCEPROP 2 LAST CDS_LIB mstr_discrete
J 0
(1175 3800);
PAINT MONO (1175 3800);
DISPLAY INVISIBLE (1175 3800);
FORCEPROP 2 LAST SEC_TYPE 0402
J 0
(1225 4025);
DISPLAY 1.021277 (1225 4025);
PAINT ORANGE (1225 4025);
DISPLAY INVISIBLE (1225 4025);
FORCEPROP 2 LAST SEC 1
J 0
(1225 4025);
DISPLAY 0.680851 (1225 4025);
PAINT MONO (1225 4025);
DISPLAY INVISIBLE (1225 4025);
FORCEPROP 2 LAST CDS_LOCATION R4P15
J 0
(1220 3925);
DISPLAY 0.617021 (1220 3925);
PAINT AQUA (1220 3925);
DISPLAY INVISIBLE (1220 3925);
FORCEPROP 1 LAST PATH I53
J 0
(1225 3975);
DISPLAY 0.978723 (1225 3975);
PAINT WHITE (1225 3975);
DISPLAY INVISIBLE (1225 3975);
FORCEPROP 2 LAST ROOM DEBUG
J 0
(1220 3965);
DISPLAY 1.276596 (1220 3965);
PAINT WHITE (1220 3965);
DISPLAY INVISIBLE (1220 3965);
FORCEADD RES..2
(1600 2400);
FORCEPROP 1 LAST LOCATION R1M4
J 0
(1645 2525);
DISPLAY 0.617021 (1645 2525);
PAINT AQUA (1645 2525);
FORCEPROP 1 LAST PART_NUMBER G21796-017
J 0
(1640 2275);
DISPLAY 0.617021 (1640 2275);
PAINT BLUE (1640 2275);
FORCEPROP 1 LAST VALUE 100.0
J 0
(1645 2475);
DISPLAY 0.617021 (1645 2475);
PAINT SKYBLUE (1645 2475);
FORCEPROP 1 LAST TOLERANCE 1%
J 0
(1645 2425);
DISPLAY 0.617021 (1645 2425);
PAINT SKYBLUE (1645 2425);
FORCEPROP 1 LAST PACK_TYPE 0402
J 0
(1640 2225);
DISPLAY 0.617021 (1640 2225);
PAINT SKYBLUE (1640 2225);
FORCEPROP 1 LAST MATERIAL CHIP
J 0
(1640 2325);
DISPLAY 0.617021 (1640 2325);
PAINT SKYBLUE (1640 2325);
FORCEPROP 1 LAST WATTAGE 1/16W
J 0
(1640 2375);
DISPLAY 0.617021 (1640 2375);
PAINT SKYBLUE (1640 2375);
FORCEPROP 1 LASTPIN (1600 2300) $PN 2
J 0
(1605 2310);
DISPLAY 0.617021 (1605 2310);
PAINT ORANGE (1605 2310);
FORCEPROP 1 LASTPIN (1600 2500) $PN 1
J 0
(1605 2462);
DISPLAY 0.617021 (1605 2462);
PAINT ORANGE (1605 2462);
FORCEPROP 2 LAST CDS_LIB mstr_discrete
J 0
(1600 2400);
PAINT ORANGE (1600 2400);
DISPLAY INVISIBLE (1600 2400);
FORCEPROP 2 LAST SEC_TYPE 0402
J 0
(1650 2625);
DISPLAY 1.021277 (1650 2625);
PAINT ORANGE (1650 2625);
DISPLAY INVISIBLE (1650 2625);
FORCEPROP 2 LAST SEC 1
J 0
(1650 2625);
DISPLAY 0.680851 (1650 2625);
PAINT MONO (1650 2625);
DISPLAY INVISIBLE (1650 2625);
FORCEPROP 2 LAST CDS_LOCATION R1M4
J 0
(1645 2525);
DISPLAY 0.617021 (1645 2525);
PAINT AQUA (1645 2525);
DISPLAY INVISIBLE (1645 2525);
FORCEPROP 1 LAST PATH I54
J 0
(1650 2575);
DISPLAY 0.978723 (1650 2575);
PAINT WHITE (1650 2575);
DISPLAY INVISIBLE (1650 2575);
FORCEPROP 2 LAST ROOM DEBUG
J 0
(1645 2565);
DISPLAY 1.276596 (1645 2565);
PAINT WHITE (1645 2565);
DISPLAY INVISIBLE (1645 2565);
FORCEADD RES..2
(1225 2400);
FORCEPROP 1 LAST LOCATION R6T7
J 0
(1270 2525);
DISPLAY 0.617021 (1270 2525);
PAINT AQUA (1270 2525);
FORCEPROP 1 LAST PART_NUMBER G21796-009
J 0
(1265 2275);
DISPLAY 0.617021 (1265 2275);
PAINT BLUE (1265 2275);
FORCEPROP 1 LAST VALUE 150.0
J 0
(1270 2475);
DISPLAY 0.617021 (1270 2475);
PAINT SKYBLUE (1270 2475);
FORCEPROP 1 LAST TOLERANCE 1%
J 0
(1270 2425);
DISPLAY 0.617021 (1270 2425);
PAINT SKYBLUE (1270 2425);
FORCEPROP 1 LAST PACK_TYPE 0402
J 0
(1265 2225);
DISPLAY 0.617021 (1265 2225);
PAINT SKYBLUE (1265 2225);
FORCEPROP 1 LAST MATERIAL CHIP
J 0
(1265 2325);
DISPLAY 0.617021 (1265 2325);
PAINT SKYBLUE (1265 2325);
FORCEPROP 1 LAST WATTAGE 1/16W
J 0
(1265 2375);
DISPLAY 0.617021 (1265 2375);
PAINT SKYBLUE (1265 2375);
FORCEPROP 1 LASTPIN (1225 2300) $PN 2
J 0
(1230 2310);
DISPLAY 0.617021 (1230 2310);
PAINT ORANGE (1230 2310);
FORCEPROP 1 LASTPIN (1225 2500) $PN 1
J 0
(1230 2462);
DISPLAY 0.617021 (1230 2462);
PAINT ORANGE (1230 2462);
FORCEPROP 2 LAST SEC_TYPE 0402
J 0
(1275 2625);
DISPLAY 1.021277 (1275 2625);
PAINT ORANGE (1275 2625);
DISPLAY INVISIBLE (1275 2625);
FORCEPROP 2 LAST CDS_LIB mstr_discrete
J 0
(1225 2400);
PAINT ORANGE (1225 2400);
DISPLAY INVISIBLE (1225 2400);
FORCEPROP 2 LAST SEC 1
J 0
(1275 2625);
DISPLAY 0.680851 (1275 2625);
PAINT MONO (1275 2625);
DISPLAY INVISIBLE (1275 2625);
FORCEPROP 2 LAST CDS_LOCATION R6T7
J 0
(1270 2525);
DISPLAY 0.617021 (1270 2525);
PAINT AQUA (1270 2525);
DISPLAY INVISIBLE (1270 2525);
FORCEPROP 1 LAST PATH I55
J 0
(1275 2575);
DISPLAY 0.978723 (1275 2575);
PAINT WHITE (1275 2575);
DISPLAY INVISIBLE (1275 2575);
FORCEPROP 2 LAST ROOM DEBUG
J 0
(1270 2565);
DISPLAY 1.276596 (1270 2565);
PAINT WHITE (1270 2565);
DISPLAY INVISIBLE (1270 2565);
FORCEADD RES..2
(875 2400);
FORCEPROP 1 LAST LOCATION R6T6
J 0
(920 2525);
DISPLAY 0.617021 (920 2525);
PAINT AQUA (920 2525);
FORCEPROP 1 LAST PART_NUMBER G21796-009
J 0
(915 2275);
DISPLAY 0.617021 (915 2275);
PAINT BLUE (915 2275);
FORCEPROP 1 LAST VALUE 150.0
J 0
(920 2475);
DISPLAY 0.617021 (920 2475);
PAINT SKYBLUE (920 2475);
FORCEPROP 1 LAST TOLERANCE 1%
J 0
(920 2425);
DISPLAY 0.617021 (920 2425);
PAINT SKYBLUE (920 2425);
FORCEPROP 1 LAST PACK_TYPE 0402
J 0
(915 2225);
DISPLAY 0.617021 (915 2225);
PAINT SKYBLUE (915 2225);
FORCEPROP 1 LAST MATERIAL CHIP
J 0
(915 2325);
DISPLAY 0.617021 (915 2325);
PAINT SKYBLUE (915 2325);
FORCEPROP 1 LAST WATTAGE 1/16W
J 0
(915 2375);
DISPLAY 0.617021 (915 2375);
PAINT SKYBLUE (915 2375);
FORCEPROP 1 LASTPIN (875 2300) $PN 2
J 0
(880 2310);
DISPLAY 0.617021 (880 2310);
PAINT ORANGE (880 2310);
FORCEPROP 1 LASTPIN (875 2500) $PN 1
J 0
(880 2462);
DISPLAY 0.617021 (880 2462);
PAINT ORANGE (880 2462);
FORCEPROP 2 LAST SEC_TYPE 0402
J 0
(925 2625);
DISPLAY 1.021277 (925 2625);
PAINT ORANGE (925 2625);
DISPLAY INVISIBLE (925 2625);
FORCEPROP 2 LAST CDS_LIB mstr_discrete
J 0
(875 2400);
PAINT ORANGE (875 2400);
DISPLAY INVISIBLE (875 2400);
FORCEPROP 2 LAST SEC 1
J 0
(925 2625);
DISPLAY 0.680851 (925 2625);
PAINT MONO (925 2625);
DISPLAY INVISIBLE (925 2625);
FORCEPROP 2 LAST CDS_LOCATION R6T6
J 0
(920 2525);
DISPLAY 0.617021 (920 2525);
PAINT AQUA (920 2525);
DISPLAY INVISIBLE (920 2525);
FORCEPROP 1 LAST PATH I56
J 0
(925 2575);
DISPLAY 0.978723 (925 2575);
PAINT WHITE (925 2575);
DISPLAY INVISIBLE (925 2575);
FORCEPROP 2 LAST ROOM DEBUG
J 0
(920 2565);
DISPLAY 1.276596 (920 2565);
PAINT WHITE (920 2565);
DISPLAY INVISIBLE (920 2565);
FORCEADD RES..2
(875 3825);
FORCEPROP 1 LAST LOCATION R4P12
J 0
(920 3950);
DISPLAY 0.617021 (920 3950);
PAINT AQUA (920 3950);
FORCEPROP 1 LAST PART_NUMBER G21796-017
J 0
(915 3700);
DISPLAY 0.617021 (915 3700);
PAINT BLUE (915 3700);
FORCEPROP 1 LAST VALUE 100.0
J 0
(920 3900);
DISPLAY 0.617021 (920 3900);
PAINT SKYBLUE (920 3900);
FORCEPROP 1 LAST TOLERANCE 1%
J 0
(920 3850);
DISPLAY 0.617021 (920 3850);
PAINT SKYBLUE (920 3850);
FORCEPROP 1 LAST PACK_TYPE 0402
J 0
(915 3650);
DISPLAY 0.617021 (915 3650);
PAINT SKYBLUE (915 3650);
FORCEPROP 1 LAST MATERIAL CHIP
J 0
(915 3750);
DISPLAY 0.617021 (915 3750);
PAINT SKYBLUE (915 3750);
FORCEPROP 1 LAST WATTAGE 1/16W
J 0
(915 3800);
DISPLAY 0.617021 (915 3800);
PAINT SKYBLUE (915 3800);
FORCEPROP 1 LASTPIN (875 3725) $PN 2
J 0
(880 3735);
DISPLAY 0.617021 (880 3735);
PAINT ORANGE (880 3735);
FORCEPROP 1 LASTPIN (875 3925) $PN 1
J 0
(880 3887);
DISPLAY 0.617021 (880 3887);
PAINT ORANGE (880 3887);
FORCEPROP 2 LAST CDS_LIB mstr_discrete
J 0
(875 3825);
PAINT MONO (875 3825);
DISPLAY INVISIBLE (875 3825);
FORCEPROP 2 LAST SEC_TYPE 0402
J 0
(925 4050);
DISPLAY 1.021277 (925 4050);
PAINT ORANGE (925 4050);
DISPLAY INVISIBLE (925 4050);
FORCEPROP 2 LAST SEC 1
J 0
(925 4050);
DISPLAY 0.680851 (925 4050);
PAINT MONO (925 4050);
DISPLAY INVISIBLE (925 4050);
FORCEPROP 2 LAST CDS_LOCATION R4P12
J 0
(920 3950);
DISPLAY 0.617021 (920 3950);
PAINT AQUA (920 3950);
DISPLAY INVISIBLE (920 3950);
FORCEPROP 1 LAST PATH I57
J 0
(925 4000);
DISPLAY 0.978723 (925 4000);
PAINT WHITE (925 4000);
DISPLAY INVISIBLE (925 4000);
FORCEPROP 2 LAST ROOM DEBUG
J 0
(920 3990);
DISPLAY 1.276596 (920 3990);
PAINT WHITE (920 3990);
DISPLAY INVISIBLE (920 3990);
FORCEADD RES..2
(575 3800);
FORCEPROP 1 LAST LOCATION R4P23
J 0
(620 3925);
DISPLAY 0.617021 (620 3925);
PAINT AQUA (620 3925);
FORCEPROP 1 LAST PART_NUMBER G21796-009
J 0
(615 3675);
DISPLAY 0.617021 (615 3675);
PAINT BLUE (615 3675);
FORCEPROP 1 LAST VALUE 150.0
J 0
(620 3875);
DISPLAY 0.617021 (620 3875);
PAINT SKYBLUE (620 3875);
FORCEPROP 1 LAST TOLERANCE 1%
J 0
(620 3825);
DISPLAY 0.617021 (620 3825);
PAINT SKYBLUE (620 3825);
FORCEPROP 1 LAST PACK_TYPE 0402
J 0
(615 3625);
DISPLAY 0.617021 (615 3625);
PAINT SKYBLUE (615 3625);
FORCEPROP 1 LAST MATERIAL CHIP
J 0
(615 3725);
DISPLAY 0.617021 (615 3725);
PAINT SKYBLUE (615 3725);
FORCEPROP 1 LAST WATTAGE 1/16W
J 0
(615 3775);
DISPLAY 0.617021 (615 3775);
PAINT SKYBLUE (615 3775);
FORCEPROP 1 LASTPIN (575 3700) $PN 2
J 0
(580 3710);
DISPLAY 0.617021 (580 3710);
PAINT ORANGE (580 3710);
FORCEPROP 1 LASTPIN (575 3900) $PN 1
J 0
(580 3862);
DISPLAY 0.617021 (580 3862);
PAINT ORANGE (580 3862);
FORCEPROP 2 LAST SEC_TYPE 0402
J 0
(625 4025);
DISPLAY 1.021277 (625 4025);
PAINT ORANGE (625 4025);
DISPLAY INVISIBLE (625 4025);
FORCEPROP 2 LAST CDS_LIB mstr_discrete
J 0
(575 3800);
PAINT ORANGE (575 3800);
DISPLAY INVISIBLE (575 3800);
FORCEPROP 2 LAST SEC 1
J 0
(625 4025);
DISPLAY 0.680851 (625 4025);
PAINT MONO (625 4025);
DISPLAY INVISIBLE (625 4025);
FORCEPROP 2 LAST CDS_LOCATION R4P23
J 0
(620 3925);
DISPLAY 0.617021 (620 3925);
PAINT AQUA (620 3925);
DISPLAY INVISIBLE (620 3925);
FORCEPROP 1 LAST PATH I58
J 0
(625 3975);
DISPLAY 0.978723 (625 3975);
PAINT WHITE (625 3975);
DISPLAY INVISIBLE (625 3975);
FORCEPROP 2 LAST ROOM DEBUG
J 0
(620 3965);
DISPLAY 1.276596 (620 3965);
PAINT WHITE (620 3965);
DISPLAY INVISIBLE (620 3965);
FORCEADD RES..2
(275 3800);
FORCEPROP 1 LAST LOCATION R4P24
J 0
(320 3925);
DISPLAY 0.617021 (320 3925);
PAINT AQUA (320 3925);
FORCEPROP 1 LAST PART_NUMBER G21796-009
J 0
(315 3675);
DISPLAY 0.617021 (315 3675);
PAINT BLUE (315 3675);
FORCEPROP 1 LAST VALUE 150.0
J 0
(320 3875);
DISPLAY 0.617021 (320 3875);
PAINT SKYBLUE (320 3875);
FORCEPROP 1 LAST TOLERANCE 1%
J 0
(320 3825);
DISPLAY 0.617021 (320 3825);
PAINT SKYBLUE (320 3825);
FORCEPROP 1 LAST PACK_TYPE 0402
J 0
(315 3625);
DISPLAY 0.617021 (315 3625);
PAINT SKYBLUE (315 3625);
FORCEPROP 1 LAST MATERIAL CHIP
J 0
(315 3725);
DISPLAY 0.617021 (315 3725);
PAINT SKYBLUE (315 3725);
FORCEPROP 1 LAST WATTAGE 1/16W
J 0
(315 3775);
DISPLAY 0.617021 (315 3775);
PAINT SKYBLUE (315 3775);
FORCEPROP 1 LASTPIN (275 3700) $PN 2
J 0
(280 3710);
DISPLAY 0.617021 (280 3710);
PAINT ORANGE (280 3710);
FORCEPROP 1 LASTPIN (275 3900) $PN 1
J 0
(280 3862);
DISPLAY 0.617021 (280 3862);
PAINT ORANGE (280 3862);
FORCEPROP 2 LAST CDS_LIB mstr_discrete
J 0
(275 3800);
PAINT ORANGE (275 3800);
DISPLAY INVISIBLE (275 3800);
FORCEPROP 2 LAST SEC_TYPE 0402
J 0
(325 4025);
DISPLAY 1.021277 (325 4025);
PAINT ORANGE (325 4025);
DISPLAY INVISIBLE (325 4025);
FORCEPROP 2 LAST SEC 1
J 0
(325 4025);
DISPLAY 0.680851 (325 4025);
PAINT MONO (325 4025);
DISPLAY INVISIBLE (325 4025);
FORCEPROP 2 LAST CDS_LOCATION R4P24
J 0
(320 3925);
DISPLAY 0.617021 (320 3925);
PAINT AQUA (320 3925);
DISPLAY INVISIBLE (320 3925);
FORCEPROP 1 LAST PATH I59
J 0
(325 3975);
DISPLAY 0.978723 (325 3975);
PAINT WHITE (325 3975);
DISPLAY INVISIBLE (325 3975);
FORCEPROP 2 LAST ROOM DEBUG
J 0
(320 3965);
DISPLAY 1.276596 (320 3965);
PAINT WHITE (320 3965);
DISPLAY INVISIBLE (320 3965);
FORCEADD RES..2
(500 2400);
FORCEPROP 1 LAST PART_NUMBER G21796-009
J 0
(540 2275);
DISPLAY 0.617021 (540 2275);
PAINT BLUE (540 2275);
FORCEPROP 1 LAST VALUE 150.0
J 0
(545 2475);
DISPLAY 0.617021 (545 2475);
PAINT SKYBLUE (545 2475);
FORCEPROP 1 LAST TOLERANCE 1%
J 0
(545 2425);
DISPLAY 0.617021 (545 2425);
PAINT SKYBLUE (545 2425);
FORCEPROP 1 LAST PACK_TYPE 0402
J 0
(540 2225);
DISPLAY 0.617021 (540 2225);
PAINT SKYBLUE (540 2225);
FORCEPROP 1 LAST MATERIAL CHIP
J 0
(540 2325);
DISPLAY 0.617021 (540 2325);
PAINT SKYBLUE (540 2325);
FORCEPROP 1 LAST WATTAGE 1/16W
J 0
(540 2375);
DISPLAY 0.617021 (540 2375);
PAINT SKYBLUE (540 2375);
FORCEPROP 1 LASTPIN (500 2300) $PN 2
J 0
(505 2310);
DISPLAY 0.617021 (505 2310);
PAINT ORANGE (505 2310);
FORCEPROP 1 LASTPIN (500 2500) $PN 1
J 0
(505 2462);
DISPLAY 0.617021 (505 2462);
PAINT ORANGE (505 2462);
FORCEPROP 1 LAST LOCATION R1L15
J 0
(545 2525);
DISPLAY 0.617021 (545 2525);
PAINT AQUA (545 2525);
FORCEPROP 2 LAST SEC_TYPE 0402
J 0
(550 2625);
DISPLAY 1.021277 (550 2625);
PAINT ORANGE (550 2625);
DISPLAY INVISIBLE (550 2625);
FORCEPROP 2 LAST CDS_LIB mstr_discrete
J 0
(500 2400);
PAINT MONO (500 2400);
DISPLAY INVISIBLE (500 2400);
FORCEPROP 2 LAST SEC 1
J 0
(550 2625);
DISPLAY 0.680851 (550 2625);
PAINT MONO (550 2625);
DISPLAY INVISIBLE (550 2625);
FORCEPROP 2 LAST CDS_LOCATION R1L15
J 0
(545 2525);
DISPLAY 0.617021 (545 2525);
PAINT AQUA (545 2525);
DISPLAY INVISIBLE (545 2525);
FORCEPROP 1 LAST PATH I60
J 0
(550 2575);
DISPLAY 0.978723 (550 2575);
PAINT WHITE (550 2575);
DISPLAY INVISIBLE (550 2575);
FORCEPROP 2 LAST ROOM DEBUG
J 0
(545 2565);
DISPLAY 1.276596 (545 2565);
PAINT WHITE (545 2565);
DISPLAY INVISIBLE (545 2565);
FORCEADD RES..2
(875 1100);
FORCEPROP 1 LAST LOCATION R7P29
J 0
(920 1225);
DISPLAY 0.617021 (920 1225);
PAINT AQUA (920 1225);
FORCEPROP 1 LAST PART_NUMBER G21796-208
J 0
(915 975);
DISPLAY 0.617021 (915 975);
PAINT BLUE (915 975);
FORCEPROP 1 LAST VALUE 51.1
J 0
(920 1175);
DISPLAY 0.617021 (920 1175);
PAINT SKYBLUE (920 1175);
FORCEPROP 1 LAST TOLERANCE 1.0%
J 0
(920 1125);
DISPLAY 0.617021 (920 1125);
PAINT SKYBLUE (920 1125);
FORCEPROP 1 LAST PACK_TYPE 0402
J 0
(915 925);
DISPLAY 0.617021 (915 925);
PAINT SKYBLUE (915 925);
FORCEPROP 1 LAST MATERIAL CHIP
J 0
(915 1025);
DISPLAY 0.617021 (915 1025);
PAINT SKYBLUE (915 1025);
FORCEPROP 1 LAST WATTAGE 1/16W
J 0
(915 1075);
DISPLAY 0.617021 (915 1075);
PAINT SKYBLUE (915 1075);
FORCEPROP 1 LASTPIN (875 1000) $PN 2
J 0
(880 1010);
DISPLAY 0.617021 (880 1010);
PAINT WHITE (880 1010);
FORCEPROP 1 LASTPIN (875 1200) $PN 1
J 0
(880 1162);
DISPLAY 0.617021 (880 1162);
PAINT WHITE (880 1162);
FORCEPROP 2 LAST CDS_LIB mstr_discrete
J 0
(875 1100);
DISPLAY 2.212766 (875 1100);
PAINT ORANGE (875 1100);
DISPLAY INVISIBLE (875 1100);
FORCEPROP 2 LAST BOM_COST DEBUG
J 0
(925 1275);
DISPLAY 1.617021 (925 1275);
PAINT WHITE (925 1275);
DISPLAY INVISIBLE (925 1275);
FORCEPROP 2 LAST CDS_SEC 1
J 0
(925 1325);
PAINT MONO (925 1325);
DISPLAY INVISIBLE (925 1325);
FORCEPROP 2 LAST $SEC 1
J 0
(925 1325);
PAINT MONO (925 1325);
DISPLAY INVISIBLE (925 1325);
FORCEPROP 2 LAST CDS_LOCATION R7P29
J 0
(920 1225);
DISPLAY 0.617021 (920 1225);
PAINT AQUA (920 1225);
DISPLAY INVISIBLE (920 1225);
FORCEPROP 1 LAST PATH I61
J 0
(925 1275);
DISPLAY 0.978723 (925 1275);
PAINT WHITE (925 1275);
DISPLAY INVISIBLE (925 1275);
FORCEPROP 2 LAST ROOM DEBUG
J 0
(925 1275);
DISPLAY 1.617021 (925 1275);
PAINT WHITE (925 1275);
DISPLAY INVISIBLE (925 1275);
FORCEADD RES..2
(500 1100);
FORCEPROP 1 LAST LOCATION R6T5
J 0
(545 1225);
DISPLAY 0.617021 (545 1225);
PAINT AQUA (545 1225);
FORCEPROP 1 LAST PART_NUMBER G21796-026
J 0
(540 975);
DISPLAY 0.617021 (540 975);
PAINT BLUE (540 975);
FORCEPROP 1 LAST VALUE 1.00K
J 0
(545 1175);
DISPLAY 0.617021 (545 1175);
PAINT SKYBLUE (545 1175);
FORCEPROP 1 LAST TOLERANCE 1%
J 0
(545 1125);
DISPLAY 0.617021 (545 1125);
PAINT SKYBLUE (545 1125);
FORCEPROP 1 LAST PACK_TYPE 0402
J 0
(540 925);
DISPLAY 0.617021 (540 925);
PAINT SKYBLUE (540 925);
FORCEPROP 1 LAST MATERIAL CHIP
J 0
(540 1025);
DISPLAY 0.617021 (540 1025);
PAINT SKYBLUE (540 1025);
FORCEPROP 1 LAST WATTAGE 1/16W
J 0
(540 1075);
DISPLAY 0.617021 (540 1075);
PAINT SKYBLUE (540 1075);
FORCEPROP 1 LASTPIN (500 1000) $PN 2
J 0
(505 1010);
DISPLAY 0.617021 (505 1010);
PAINT ORANGE (505 1010);
FORCEPROP 1 LASTPIN (500 1200) $PN 1
J 0
(505 1162);
DISPLAY 0.617021 (505 1162);
PAINT ORANGE (505 1162);
FORCEPROP 2 LAST BOM_COST DEBUG
J 0
(550 1275);
DISPLAY 1.617021 (550 1275);
PAINT WHITE (550 1275);
DISPLAY INVISIBLE (550 1275);
FORCEPROP 2 LAST CDS_LIB mstr_discrete
J 0
(500 1100);
PAINT MONO (500 1100);
DISPLAY INVISIBLE (500 1100);
FORCEPROP 2 LAST SEC_TYPE 0402
J 0
(550 1325);
DISPLAY 1.021277 (550 1325);
PAINT ORANGE (550 1325);
DISPLAY INVISIBLE (550 1325);
FORCEPROP 2 LAST SEC 1
J 0
(550 1325);
DISPLAY 0.680851 (550 1325);
PAINT MONO (550 1325);
DISPLAY INVISIBLE (550 1325);
FORCEPROP 2 LAST CDS_LOCATION R6T5
J 0
(545 1225);
DISPLAY 0.617021 (545 1225);
PAINT AQUA (545 1225);
DISPLAY INVISIBLE (545 1225);
FORCEPROP 1 LAST PATH I62
J 0
(550 1275);
DISPLAY 0.978723 (550 1275);
PAINT WHITE (550 1275);
DISPLAY INVISIBLE (550 1275);
FORCEPROP 2 LAST ROOM DEBUG
J 0
(550 1275);
DISPLAY 1.617021 (550 1275);
PAINT WHITE (550 1275);
DISPLAY INVISIBLE (550 1275);
FORCEADD OFFPAGE..1
(-100 2250);
FORCEPROP 2 LAST $XR2 55 
J 0
(-532 2250);
DISPLAY 0.638298 (-532 2250);
PAINT MONO (-532 2250);
FORCEPROP 2 LAST $XR1 21 
J 0
(-442 2250);
DISPLAY 0.638298 (-442 2250);
PAINT MONO (-442 2250);
FORCEPROP 2 LAST $XR0 112 
J 0
(-352 2250);
DISPLAY 0.638298 (-352 2250);
PAINT MONO (-352 2250);
FORCEPROP 2 LAST CDS_LIB mstr_standard
J 0
(-100 2250);
DISPLAY 2.212766 (-100 2250);
PAINT ORANGE (-100 2250);
DISPLAY INVISIBLE (-100 2250);
FORCEPROP 2 LAST PATH I63
J 0
(-350 2300);
DISPLAY 1.021277 (-350 2300);
PAINT ORANGE (-350 2300);
DISPLAY INVISIBLE (-350 2300);
FORCEPROP 1 LAST OFFPAGE TRUE
J 0
(225 2125);
DISPLAY 1.404255 (225 2125);
PAINT GREEN (225 2125);
DISPLAY INVISIBLE (225 2125);
FORCEPROP 1 LAST COMMENT_BODY TRUE
J 0
(25 2150);
DISPLAY 1.404255 (25 2150);
PAINT PEACH (25 2150);
DISPLAY INVISIBLE (25 2150);
FORCEADD OFFPAGE..1
(-100 2175);
FORCEPROP 2 LAST $XR1 55 
J 0
(-442 2175);
DISPLAY 0.638298 (-442 2175);
PAINT MONO (-442 2175);
FORCEPROP 2 LAST $XR0 112 
J 0
(-352 2175);
DISPLAY 0.638298 (-352 2175);
PAINT MONO (-352 2175);
FORCEPROP 2 LAST CDS_LIB mstr_standard
J 0
(-100 2175);
DISPLAY 2.212766 (-100 2175);
PAINT ORANGE (-100 2175);
DISPLAY INVISIBLE (-100 2175);
FORCEPROP 2 LAST PATH I64
J 0
(-350 2225);
DISPLAY 1.021277 (-350 2225);
PAINT ORANGE (-350 2225);
DISPLAY INVISIBLE (-350 2225);
FORCEPROP 1 LAST OFFPAGE TRUE
J 0
(225 2050);
DISPLAY 1.404255 (225 2050);
PAINT GREEN (225 2050);
DISPLAY INVISIBLE (225 2050);
FORCEPROP 1 LAST COMMENT_BODY TRUE
J 0
(25 2075);
DISPLAY 1.404255 (25 2075);
PAINT PEACH (25 2075);
DISPLAY INVISIBLE (25 2075);
FORCEADD OFFPAGE..1
(-100 2100);
FORCEPROP 2 LAST $XR1 112 
J 0
(-441 2100);
DISPLAY 0.638298 (-441 2100);
PAINT MONO (-441 2100);
FORCEPROP 2 LAST $XR0 55 
J 0
(-321 2100);
DISPLAY 0.638298 (-321 2100);
PAINT MONO (-321 2100);
FORCEPROP 2 LAST CDS_LIB mstr_standard
J 0
(-100 2100);
DISPLAY 2.212766 (-100 2100);
PAINT ORANGE (-100 2100);
DISPLAY INVISIBLE (-100 2100);
FORCEPROP 2 LAST PATH I65
J 0
(-300 2150);
DISPLAY 1.021277 (-300 2150);
PAINT ORANGE (-300 2150);
DISPLAY INVISIBLE (-300 2150);
FORCEPROP 1 LAST OFFPAGE TRUE
J 0
(225 1975);
DISPLAY 1.404255 (225 1975);
PAINT GREEN (225 1975);
DISPLAY INVISIBLE (225 1975);
FORCEPROP 1 LAST COMMENT_BODY TRUE
J 0
(25 2000);
DISPLAY 1.404255 (25 2000);
PAINT PEACH (25 2000);
DISPLAY INVISIBLE (25 2000);
FORCEADD OFFPAGE..1
(-100 2025);
FORCEPROP 2 LAST $XR2 55 
J 0
(-532 2025);
DISPLAY 0.638298 (-532 2025);
PAINT MONO (-532 2025);
FORCEPROP 2 LAST $XR1 21 
J 0
(-442 2025);
DISPLAY 0.638298 (-442 2025);
PAINT MONO (-442 2025);
FORCEPROP 2 LAST $XR0 112 
J 0
(-352 2025);
DISPLAY 0.638298 (-352 2025);
PAINT MONO (-352 2025);
FORCEPROP 2 LAST CDS_LIB mstr_standard
J 0
(-100 2025);
DISPLAY 2.212766 (-100 2025);
PAINT ORANGE (-100 2025);
DISPLAY INVISIBLE (-100 2025);
FORCEPROP 2 LAST PATH I66
J 0
(-350 2075);
DISPLAY 1.021277 (-350 2075);
PAINT ORANGE (-350 2075);
DISPLAY INVISIBLE (-350 2075);
FORCEPROP 1 LAST OFFPAGE TRUE
J 0
(225 1900);
DISPLAY 1.404255 (225 1900);
PAINT GREEN (225 1900);
DISPLAY INVISIBLE (225 1900);
FORCEPROP 1 LAST COMMENT_BODY TRUE
J 0
(25 1925);
DISPLAY 1.404255 (25 1925);
PAINT PEACH (25 1925);
DISPLAY INVISIBLE (25 1925);
FORCEADD OFFPAGE..1
(-100 1950);
FORCEPROP 2 LAST $XR2 112 
J 0
(-531 1950);
DISPLAY 0.638298 (-531 1950);
PAINT MONO (-531 1950);
FORCEPROP 2 LAST $XR1 55 
J 0
(-411 1950);
DISPLAY 0.638298 (-411 1950);
PAINT MONO (-411 1950);
FORCEPROP 2 LAST $XR0 21 
J 0
(-321 1950);
DISPLAY 0.638298 (-321 1950);
PAINT MONO (-321 1950);
FORCEPROP 2 LAST CDS_LIB mstr_standard
J 0
(-100 1950);
DISPLAY 2.212766 (-100 1950);
PAINT ORANGE (-100 1950);
DISPLAY INVISIBLE (-100 1950);
FORCEPROP 2 LAST PATH I67
J 0
(-275 2000);
DISPLAY 1.021277 (-275 2000);
PAINT ORANGE (-275 2000);
DISPLAY INVISIBLE (-275 2000);
FORCEPROP 1 LAST OFFPAGE TRUE
J 0
(225 1825);
DISPLAY 1.404255 (225 1825);
PAINT GREEN (225 1825);
DISPLAY INVISIBLE (225 1825);
FORCEPROP 1 LAST COMMENT_BODY TRUE
J 0
(25 1850);
DISPLAY 1.404255 (25 1850);
PAINT PEACH (25 1850);
DISPLAY INVISIBLE (25 1850);
FORCEADD OFFPAGE..1
(-100 1875);
FORCEPROP 2 LAST $XR2 112 
J 0
(-531 1875);
DISPLAY 0.638298 (-531 1875);
PAINT MONO (-531 1875);
FORCEPROP 2 LAST $XR1 55 
J 0
(-411 1875);
DISPLAY 0.638298 (-411 1875);
PAINT MONO (-411 1875);
FORCEPROP 2 LAST $XR0 21 
J 0
(-321 1875);
DISPLAY 0.638298 (-321 1875);
PAINT MONO (-321 1875);
FORCEPROP 2 LAST CDS_LIB mstr_standard
J 0
(-100 1875);
DISPLAY 2.212766 (-100 1875);
PAINT ORANGE (-100 1875);
DISPLAY INVISIBLE (-100 1875);
FORCEPROP 2 LAST PATH I68
J 0
(-275 1925);
DISPLAY 1.021277 (-275 1925);
PAINT ORANGE (-275 1925);
DISPLAY INVISIBLE (-275 1925);
FORCEPROP 1 LAST OFFPAGE TRUE
J 0
(225 1750);
DISPLAY 1.404255 (225 1750);
PAINT GREEN (225 1750);
DISPLAY INVISIBLE (225 1750);
FORCEPROP 1 LAST COMMENT_BODY TRUE
J 0
(25 1775);
DISPLAY 1.404255 (25 1775);
PAINT PEACH (25 1775);
DISPLAY INVISIBLE (25 1775);
FORCEADD OFFPAGE..1
(-100 1800);
FORCEPROP 2 LAST $XR2 112 
J 0
(-531 1800);
DISPLAY 0.638298 (-531 1800);
PAINT MONO (-531 1800);
FORCEPROP 2 LAST $XR1 55 
J 0
(-411 1800);
DISPLAY 0.638298 (-411 1800);
PAINT MONO (-411 1800);
FORCEPROP 2 LAST $XR0 21 
J 0
(-321 1800);
DISPLAY 0.638298 (-321 1800);
PAINT MONO (-321 1800);
FORCEPROP 2 LAST CDS_LIB mstr_standard
J 0
(-100 1800);
DISPLAY 2.212766 (-100 1800);
PAINT ORANGE (-100 1800);
DISPLAY INVISIBLE (-100 1800);
FORCEPROP 2 LAST PATH I69
J 0
(-275 1850);
DISPLAY 1.021277 (-275 1850);
PAINT ORANGE (-275 1850);
DISPLAY INVISIBLE (-275 1850);
FORCEPROP 1 LAST OFFPAGE TRUE
J 0
(225 1675);
DISPLAY 1.404255 (225 1675);
PAINT GREEN (225 1675);
DISPLAY INVISIBLE (225 1675);
FORCEPROP 1 LAST COMMENT_BODY TRUE
J 0
(25 1700);
DISPLAY 1.404255 (25 1700);
PAINT PEACH (25 1700);
DISPLAY INVISIBLE (25 1700);
FORCEADD OFFPAGE..1
(-100 1575);
FORCEPROP 2 LAST $XR2 112 
J 0
(-531 1575);
DISPLAY 0.638298 (-531 1575);
PAINT MONO (-531 1575);
FORCEPROP 2 LAST $XR1 55 
J 0
(-411 1575);
DISPLAY 0.638298 (-411 1575);
PAINT MONO (-411 1575);
FORCEPROP 2 LAST $XR0 21 
J 0
(-321 1575);
DISPLAY 0.638298 (-321 1575);
PAINT MONO (-321 1575);
FORCEPROP 2 LAST CDS_LIB mstr_standard
J 0
(-100 1575);
DISPLAY 2.212766 (-100 1575);
PAINT ORANGE (-100 1575);
DISPLAY INVISIBLE (-100 1575);
FORCEPROP 2 LAST PATH I70
J 0
(-350 1625);
DISPLAY 1.021277 (-350 1625);
PAINT ORANGE (-350 1625);
DISPLAY INVISIBLE (-350 1625);
FORCEPROP 1 LAST OFFPAGE TRUE
J 0
(225 1450);
DISPLAY 1.404255 (225 1450);
PAINT GREEN (225 1450);
DISPLAY INVISIBLE (225 1450);
FORCEPROP 1 LAST COMMENT_BODY TRUE
J 0
(25 1475);
DISPLAY 1.404255 (25 1475);
PAINT PEACH (25 1475);
DISPLAY INVISIBLE (25 1475);
FORCEADD OFFPAGE..1
(-100 1425);
FORCEPROP 2 LAST $XR3 55 
J 0
(-652 1425);
DISPLAY 0.638298 (-652 1425);
PAINT MONO (-652 1425);
FORCEPROP 2 LAST $XR2 21 
J 0
(-562 1425);
DISPLAY 0.638298 (-562 1425);
PAINT MONO (-562 1425);
FORCEPROP 2 LAST $XR1 254 
J 0
(-472 1425);
DISPLAY 0.638298 (-472 1425);
PAINT MONO (-472 1425);
FORCEPROP 2 LAST $XR0 111 
J 0
(-352 1425);
DISPLAY 0.638298 (-352 1425);
PAINT MONO (-352 1425);
FORCEPROP 2 LAST CDS_LIB mstr_standard
J 0
(-100 1425);
DISPLAY 2.212766 (-100 1425);
PAINT ORANGE (-100 1425);
DISPLAY INVISIBLE (-100 1425);
FORCEPROP 2 LAST PATH I71
J 0
(-350 1475);
DISPLAY 1.021277 (-350 1475);
PAINT ORANGE (-350 1475);
DISPLAY INVISIBLE (-350 1475);
FORCEPROP 1 LAST OFFPAGE TRUE
J 0
(225 1300);
DISPLAY 1.404255 (225 1300);
PAINT GREEN (225 1300);
DISPLAY INVISIBLE (225 1300);
FORCEPROP 1 LAST COMMENT_BODY TRUE
J 0
(25 1325);
DISPLAY 1.404255 (25 1325);
PAINT PEACH (25 1325);
DISPLAY INVISIBLE (25 1325);
FORCEADD OFFPAGE..1
(-100 1500);
FORCEPROP 2 LAST $XR2 112 
J 0
(-531 1500);
DISPLAY 0.638298 (-531 1500);
PAINT MONO (-531 1500);
FORCEPROP 2 LAST $XR1 55 
J 0
(-411 1500);
DISPLAY 0.638298 (-411 1500);
PAINT MONO (-411 1500);
FORCEPROP 2 LAST $XR0 21 
J 0
(-321 1500);
DISPLAY 0.638298 (-321 1500);
PAINT MONO (-321 1500);
FORCEPROP 2 LAST CDS_LIB mstr_standard
J 0
(-100 1500);
DISPLAY 2.212766 (-100 1500);
PAINT ORANGE (-100 1500);
DISPLAY INVISIBLE (-100 1500);
FORCEPROP 2 LAST PATH I72
J 0
(-350 1550);
DISPLAY 1.021277 (-350 1550);
PAINT ORANGE (-350 1550);
DISPLAY INVISIBLE (-350 1550);
FORCEPROP 1 LAST OFFPAGE TRUE
J 0
(225 1375);
DISPLAY 1.404255 (225 1375);
PAINT GREEN (225 1375);
DISPLAY INVISIBLE (225 1375);
FORCEPROP 1 LAST COMMENT_BODY TRUE
J 0
(25 1400);
DISPLAY 1.404255 (25 1400);
PAINT PEACH (25 1400);
DISPLAY INVISIBLE (25 1400);
FORCEADD OFFPAGE..1
(-100 1350);
FORCEPROP 2 LAST $XR2 55 
J 0
(-532 1350);
DISPLAY 0.638298 (-532 1350);
PAINT MONO (-532 1350);
FORCEPROP 2 LAST $XR1 21 
J 0
(-442 1350);
DISPLAY 0.638298 (-442 1350);
PAINT MONO (-442 1350);
FORCEPROP 2 LAST $XR0 112 
J 0
(-352 1350);
DISPLAY 0.638298 (-352 1350);
PAINT MONO (-352 1350);
FORCEPROP 2 LAST CDS_LIB mstr_standard
J 0
(-100 1350);
DISPLAY 2.212766 (-100 1350);
PAINT ORANGE (-100 1350);
DISPLAY INVISIBLE (-100 1350);
FORCEPROP 2 LAST PATH I73
J 0
(-350 1400);
DISPLAY 1.021277 (-350 1400);
PAINT ORANGE (-350 1400);
DISPLAY INVISIBLE (-350 1400);
FORCEPROP 1 LAST OFFPAGE TRUE
J 0
(225 1225);
DISPLAY 1.404255 (225 1225);
PAINT GREEN (225 1225);
DISPLAY INVISIBLE (225 1225);
FORCEPROP 1 LAST COMMENT_BODY TRUE
J 0
(25 1250);
DISPLAY 1.404255 (25 1250);
PAINT PEACH (25 1250);
DISPLAY INVISIBLE (25 1250);
FORCEADD GND..1
(500 725);
FORCEPROP 3 LASTPIN (500 775) SIG_NAME GND\g
J 0
(510 785);
DISPLAY 0.659574 (510 785);
PAINT MONO (510 785);
DISPLAY INVISIBLE (510 785);
FORCEPROP 1 LAST VOLTAGE 0.0V
J 0
(455 682);
DISPLAY 0.340426 (455 682);
PAINT SKYBLUE (455 682);
DISPLAY INVISIBLE (455 682);
FORCEPROP 1 LAST SIZE 1B
J 0
(575 675);
DISPLAY 2.382979 (575 675);
PAINT GREEN (575 675);
DISPLAY INVISIBLE (575 675);
FORCEPROP 2 LAST CDS_LIB mstr_symbols
J 0
(500 725);
DISPLAY 2.212766 (500 725);
PAINT ORANGE (500 725);
DISPLAY INVISIBLE (500 725);
FORCEPROP 1 LAST PATH I74
J 0
(575 725);
DISPLAY 0.872340 (575 725);
PAINT AQUA (575 725);
DISPLAY INVISIBLE (575 725);
FORCEPROP 1 LAST BODY_TYPE PLUMBING
J 0
(455 682);
DISPLAY 0.340426 (455 682);
PAINT GREEN (455 682);
DISPLAY INVISIBLE (455 682);
FORCEPROP 1 LAST HDL_POWER GND
J 0
(500 875);
PAINT GREEN (500 875);
DISPLAY INVISIBLE (500 875);
FORCEADD RES..2
(-1200 4425);
FORCEPROP 1 LAST LOCATION R1L39
J 0
(-1155 4550);
DISPLAY 0.617021 (-1155 4550);
PAINT AQUA (-1155 4550);
FORCEPROP 1 LAST PART_NUMBER G21796-017
J 0
(-1160 4300);
DISPLAY 0.617021 (-1160 4300);
PAINT BLUE (-1160 4300);
FORCEPROP 1 LAST VALUE 100.0
J 0
(-1155 4500);
DISPLAY 0.617021 (-1155 4500);
PAINT SKYBLUE (-1155 4500);
FORCEPROP 1 LAST PACK_TYPE 0402
J 0
(-1160 4250);
DISPLAY 0.617021 (-1160 4250);
PAINT SKYBLUE (-1160 4250);
FORCEPROP 1 LAST WATTAGE 1/16W
J 0
(-1160 4400);
DISPLAY 0.617021 (-1160 4400);
PAINT SKYBLUE (-1160 4400);
FORCEPROP 1 LASTPIN (-1200 4325) $PN 2
J 0
(-1195 4335);
DISPLAY 0.617021 (-1195 4335);
PAINT ORANGE (-1195 4335);
FORCEPROP 1 LASTPIN (-1200 4525) $PN 1
J 0
(-1195 4487);
DISPLAY 0.617021 (-1195 4487);
PAINT ORANGE (-1195 4487);
FORCEPROP 1 LAST MATERIAL CHIP
J 0
(-1160 4350);
DISPLAY 0.617021 (-1160 4350);
PAINT SKYBLUE (-1160 4350);
FORCEPROP 1 LAST TOLERANCE 1%
J 0
(-1155 4450);
DISPLAY 0.617021 (-1155 4450);
PAINT SKYBLUE (-1155 4450);
FORCEPROP 2 LAST CDS_LIB mstr_discrete
J 0
(-1200 4425);
PAINT ORANGE (-1200 4425);
DISPLAY INVISIBLE (-1200 4425);
FORCEPROP 2 LAST SEC_TYPE 0402
J 0
(-1150 4650);
DISPLAY 1.021277 (-1150 4650);
PAINT ORANGE (-1150 4650);
DISPLAY INVISIBLE (-1150 4650);
FORCEPROP 2 LAST SEC 1
J 0
(-1150 4650);
DISPLAY 0.680851 (-1150 4650);
PAINT MONO (-1150 4650);
DISPLAY INVISIBLE (-1150 4650);
FORCEPROP 2 LAST CDS_LOCATION R1L39
J 0
(-1155 4550);
DISPLAY 0.617021 (-1155 4550);
PAINT AQUA (-1155 4550);
DISPLAY INVISIBLE (-1155 4550);
FORCEPROP 1 LAST PATH I76
J 0
(-1150 4600);
DISPLAY 0.978723 (-1150 4600);
PAINT WHITE (-1150 4600);
DISPLAY INVISIBLE (-1150 4600);
FORCEPROP 2 LAST ROOM DEBUG
J 0
(-1155 4590);
DISPLAY 1.276596 (-1155 4590);
PAINT WHITE (-1155 4590);
DISPLAY INVISIBLE (-1155 4590);
FORCEADD RES..2
(-1575 4425);
FORCEPROP 1 LAST LOCATION R1L41
J 0
(-1530 4550);
DISPLAY 0.617021 (-1530 4550);
PAINT AQUA (-1530 4550);
FORCEPROP 1 LAST PART_NUMBER G21796-017
J 0
(-1535 4300);
DISPLAY 0.617021 (-1535 4300);
PAINT BLUE (-1535 4300);
FORCEPROP 1 LAST VALUE 100.0
J 0
(-1530 4500);
DISPLAY 0.617021 (-1530 4500);
PAINT SKYBLUE (-1530 4500);
FORCEPROP 1 LAST TOLERANCE 1%
J 0
(-1530 4450);
DISPLAY 0.617021 (-1530 4450);
PAINT SKYBLUE (-1530 4450);
FORCEPROP 1 LAST PACK_TYPE 0402
J 0
(-1535 4250);
DISPLAY 0.617021 (-1535 4250);
PAINT SKYBLUE (-1535 4250);
FORCEPROP 1 LAST MATERIAL CHIP
J 0
(-1535 4350);
DISPLAY 0.617021 (-1535 4350);
PAINT SKYBLUE (-1535 4350);
FORCEPROP 1 LAST WATTAGE 1/16W
J 0
(-1535 4400);
DISPLAY 0.617021 (-1535 4400);
PAINT SKYBLUE (-1535 4400);
FORCEPROP 1 LASTPIN (-1575 4325) $PN 2
J 0
(-1570 4335);
DISPLAY 0.617021 (-1570 4335);
PAINT ORANGE (-1570 4335);
FORCEPROP 1 LASTPIN (-1575 4525) $PN 1
J 0
(-1570 4487);
DISPLAY 0.617021 (-1570 4487);
PAINT ORANGE (-1570 4487);
FORCEPROP 2 LAST SEC_TYPE 0402
J 0
(-1525 4650);
DISPLAY 1.021277 (-1525 4650);
PAINT ORANGE (-1525 4650);
DISPLAY INVISIBLE (-1525 4650);
FORCEPROP 2 LAST CDS_LIB mstr_discrete
J 0
(-1575 4425);
PAINT ORANGE (-1575 4425);
DISPLAY INVISIBLE (-1575 4425);
FORCEPROP 2 LAST SEC 1
J 0
(-1525 4650);
DISPLAY 0.680851 (-1525 4650);
PAINT MONO (-1525 4650);
DISPLAY INVISIBLE (-1525 4650);
FORCEPROP 2 LAST CDS_LOCATION R1L41
J 0
(-1530 4550);
DISPLAY 0.617021 (-1530 4550);
PAINT AQUA (-1530 4550);
DISPLAY INVISIBLE (-1530 4550);
FORCEPROP 1 LAST PATH I77
J 0
(-1525 4600);
DISPLAY 0.978723 (-1525 4600);
PAINT WHITE (-1525 4600);
DISPLAY INVISIBLE (-1525 4600);
FORCEPROP 2 LAST ROOM DEBUG
J 0
(-1530 4590);
DISPLAY 1.276596 (-1530 4590);
PAINT WHITE (-1530 4590);
DISPLAY INVISIBLE (-1530 4590);
FORCEADD RES..2
(-1950 4425);
FORCEPROP 1 LAST LOCATION R9A11
J 0
(-1905 4550);
DISPLAY 0.617021 (-1905 4550);
PAINT AQUA (-1905 4550);
FORCEPROP 1 LAST PART_NUMBER G21796-009
J 0
(-1910 4300);
DISPLAY 0.617021 (-1910 4300);
PAINT BLUE (-1910 4300);
FORCEPROP 1 LAST VALUE 150.0
J 0
(-1905 4500);
DISPLAY 0.617021 (-1905 4500);
PAINT SKYBLUE (-1905 4500);
FORCEPROP 1 LAST TOLERANCE 1%
J 0
(-1905 4450);
DISPLAY 0.617021 (-1905 4450);
PAINT SKYBLUE (-1905 4450);
FORCEPROP 1 LAST MATERIAL CHIP
J 0
(-1910 4350);
DISPLAY 0.617021 (-1910 4350);
PAINT SKYBLUE (-1910 4350);
FORCEPROP 1 LAST WATTAGE 1/16W
J 0
(-1910 4400);
DISPLAY 0.617021 (-1910 4400);
PAINT SKYBLUE (-1910 4400);
FORCEPROP 1 LASTPIN (-1950 4325) $PN 2
J 0
(-1945 4335);
DISPLAY 0.617021 (-1945 4335);
PAINT ORANGE (-1945 4335);
FORCEPROP 1 LASTPIN (-1950 4525) $PN 1
J 0
(-1945 4487);
DISPLAY 0.617021 (-1945 4487);
PAINT ORANGE (-1945 4487);
FORCEPROP 1 LAST PACK_TYPE 0402
J 0
(-1910 4250);
DISPLAY 0.617021 (-1910 4250);
PAINT SKYBLUE (-1910 4250);
FORCEPROP 2 LAST CDS_LIB mstr_discrete
J 0
(-1950 4425);
PAINT ORANGE (-1950 4425);
DISPLAY INVISIBLE (-1950 4425);
FORCEPROP 2 LAST SEC_TYPE 0402
J 0
(-1900 4650);
DISPLAY 1.021277 (-1900 4650);
PAINT ORANGE (-1900 4650);
DISPLAY INVISIBLE (-1900 4650);
FORCEPROP 2 LAST SEC 1
J 0
(-1900 4650);
DISPLAY 0.680851 (-1900 4650);
PAINT MONO (-1900 4650);
DISPLAY INVISIBLE (-1900 4650);
FORCEPROP 2 LAST CDS_LOCATION R9A11
J 0
(-1905 4550);
DISPLAY 0.617021 (-1905 4550);
PAINT AQUA (-1905 4550);
DISPLAY INVISIBLE (-1905 4550);
FORCEPROP 1 LAST PATH I78
J 0
(-1900 4600);
DISPLAY 0.978723 (-1900 4600);
PAINT WHITE (-1900 4600);
DISPLAY INVISIBLE (-1900 4600);
FORCEPROP 2 LAST ROOM DEBUG
J 0
(-1905 4590);
DISPLAY 1.276596 (-1905 4590);
PAINT WHITE (-1905 4590);
DISPLAY INVISIBLE (-1905 4590);
FORCEADD RES..2
(-2325 4425);
FORCEPROP 1 LAST LOCATION R8A13
J 0
(-2280 4550);
DISPLAY 0.617021 (-2280 4550);
PAINT AQUA (-2280 4550);
FORCEPROP 1 LAST VALUE 150.0
J 0
(-2280 4500);
DISPLAY 0.617021 (-2280 4500);
PAINT SKYBLUE (-2280 4500);
FORCEPROP 1 LAST TOLERANCE 1%
J 0
(-2280 4450);
DISPLAY 0.617021 (-2280 4450);
PAINT SKYBLUE (-2280 4450);
FORCEPROP 1 LAST PACK_TYPE 0402
J 0
(-2285 4250);
DISPLAY 0.617021 (-2285 4250);
PAINT SKYBLUE (-2285 4250);
FORCEPROP 1 LAST MATERIAL CHIP
J 0
(-2285 4350);
DISPLAY 0.617021 (-2285 4350);
PAINT SKYBLUE (-2285 4350);
FORCEPROP 1 LAST WATTAGE 1/16W
J 0
(-2285 4400);
DISPLAY 0.617021 (-2285 4400);
PAINT SKYBLUE (-2285 4400);
FORCEPROP 1 LASTPIN (-2325 4325) $PN 2
J 0
(-2320 4335);
DISPLAY 0.617021 (-2320 4335);
PAINT ORANGE (-2320 4335);
FORCEPROP 1 LASTPIN (-2325 4525) $PN 1
J 0
(-2320 4487);
DISPLAY 0.617021 (-2320 4487);
PAINT ORANGE (-2320 4487);
FORCEPROP 1 LAST PART_NUMBER G21796-009
J 0
(-2285 4300);
DISPLAY 0.617021 (-2285 4300);
PAINT BLUE (-2285 4300);
FORCEPROP 2 LAST CDS_LIB mstr_discrete
J 0
(-2325 4425);
PAINT ORANGE (-2325 4425);
DISPLAY INVISIBLE (-2325 4425);
FORCEPROP 2 LAST SEC_TYPE 0402
J 0
(-2275 4650);
DISPLAY 1.021277 (-2275 4650);
PAINT ORANGE (-2275 4650);
DISPLAY INVISIBLE (-2275 4650);
FORCEPROP 2 LAST SEC 1
J 0
(-2275 4650);
DISPLAY 0.680851 (-2275 4650);
PAINT MONO (-2275 4650);
DISPLAY INVISIBLE (-2275 4650);
FORCEPROP 2 LAST CDS_LOCATION R8A13
J 0
(-2280 4550);
DISPLAY 0.617021 (-2280 4550);
PAINT AQUA (-2280 4550);
DISPLAY INVISIBLE (-2280 4550);
FORCEPROP 1 LAST PATH I79
J 0
(-2275 4600);
DISPLAY 0.978723 (-2275 4600);
PAINT WHITE (-2275 4600);
DISPLAY INVISIBLE (-2275 4600);
FORCEPROP 2 LAST ROOM DEBUG
J 0
(-2280 4590);
DISPLAY 1.276596 (-2280 4590);
PAINT WHITE (-2280 4590);
DISPLAY INVISIBLE (-2280 4590);
FORCEADD RES..2
(-2700 4425);
FORCEPROP 1 LAST LOCATION R8A14
J 0
(-2655 4550);
DISPLAY 0.617021 (-2655 4550);
PAINT AQUA (-2655 4550);
FORCEPROP 1 LAST VALUE 150.0
J 0
(-2655 4500);
DISPLAY 0.617021 (-2655 4500);
PAINT SKYBLUE (-2655 4500);
FORCEPROP 1 LAST TOLERANCE 1%
J 0
(-2655 4450);
DISPLAY 0.617021 (-2655 4450);
PAINT SKYBLUE (-2655 4450);
FORCEPROP 1 LAST PACK_TYPE 0402
J 0
(-2660 4250);
DISPLAY 0.617021 (-2660 4250);
PAINT SKYBLUE (-2660 4250);
FORCEPROP 1 LAST MATERIAL CHIP
J 0
(-2660 4350);
DISPLAY 0.617021 (-2660 4350);
PAINT SKYBLUE (-2660 4350);
FORCEPROP 1 LAST WATTAGE 1/16W
J 0
(-2660 4400);
DISPLAY 0.617021 (-2660 4400);
PAINT SKYBLUE (-2660 4400);
FORCEPROP 1 LASTPIN (-2700 4325) $PN 2
J 0
(-2695 4335);
DISPLAY 0.617021 (-2695 4335);
PAINT ORANGE (-2695 4335);
FORCEPROP 1 LASTPIN (-2700 4525) $PN 1
J 0
(-2695 4487);
DISPLAY 0.617021 (-2695 4487);
PAINT ORANGE (-2695 4487);
FORCEPROP 1 LAST PART_NUMBER G21796-009
J 0
(-2660 4300);
DISPLAY 0.617021 (-2660 4300);
PAINT BLUE (-2660 4300);
FORCEPROP 2 LAST CDS_LIB mstr_discrete
J 0
(-2700 4425);
PAINT ORANGE (-2700 4425);
DISPLAY INVISIBLE (-2700 4425);
FORCEPROP 2 LAST SEC_TYPE 0402
J 0
(-2650 4650);
DISPLAY 1.021277 (-2650 4650);
PAINT ORANGE (-2650 4650);
DISPLAY INVISIBLE (-2650 4650);
FORCEPROP 2 LAST SEC 1
J 0
(-2650 4650);
DISPLAY 0.680851 (-2650 4650);
PAINT MONO (-2650 4650);
DISPLAY INVISIBLE (-2650 4650);
FORCEPROP 2 LAST CDS_LOCATION R8A14
J 0
(-2655 4550);
DISPLAY 0.617021 (-2655 4550);
PAINT AQUA (-2655 4550);
DISPLAY INVISIBLE (-2655 4550);
FORCEPROP 1 LAST PATH I80
J 0
(-2650 4600);
DISPLAY 0.978723 (-2650 4600);
PAINT WHITE (-2650 4600);
DISPLAY INVISIBLE (-2650 4600);
FORCEPROP 2 LAST ROOM DEBUG
J 0
(-2655 4590);
DISPLAY 1.276596 (-2655 4590);
PAINT WHITE (-2655 4590);
DISPLAY INVISIBLE (-2655 4590);
FORCEADD OFFPAGE..1
(-300 3650);
FORCEPROP 2 LAST $XR1 21 
J 0
(-642 3650);
DISPLAY 0.638298 (-642 3650);
PAINT MONO (-642 3650);
FORCEPROP 2 LAST $XR0 112 
J 0
(-552 3650);
DISPLAY 0.638298 (-552 3650);
PAINT MONO (-552 3650);
FORCEPROP 2 LAST CDS_LIB mstr_standard
J 0
(-300 3650);
DISPLAY 2.212766 (-300 3650);
PAINT ORANGE (-300 3650);
DISPLAY INVISIBLE (-300 3650);
FORCEPROP 2 LAST PATH I81
J 0
(-550 3700);
DISPLAY 1.021277 (-550 3700);
PAINT ORANGE (-550 3700);
DISPLAY INVISIBLE (-550 3700);
FORCEPROP 1 LAST OFFPAGE TRUE
J 0
(25 3525);
DISPLAY 1.404255 (25 3525);
PAINT GREEN (25 3525);
DISPLAY INVISIBLE (25 3525);
FORCEPROP 1 LAST COMMENT_BODY TRUE
J 0
(-175 3550);
DISPLAY 1.404255 (-175 3550);
PAINT PEACH (-175 3550);
DISPLAY INVISIBLE (-175 3550);
FORCEADD OFFPAGE..1
(-300 3575);
FORCEPROP 2 LAST $XR1 112 
J 0
(-641 3575);
DISPLAY 0.638298 (-641 3575);
PAINT MONO (-641 3575);
FORCEPROP 2 LAST $XR0 21 
J 0
(-521 3575);
DISPLAY 0.638298 (-521 3575);
PAINT MONO (-521 3575);
FORCEPROP 2 LAST CDS_LIB mstr_standard
J 0
(-300 3575);
DISPLAY 2.212766 (-300 3575);
PAINT ORANGE (-300 3575);
DISPLAY INVISIBLE (-300 3575);
FORCEPROP 2 LAST PATH I82
J 0
(-500 3625);
DISPLAY 1.021277 (-500 3625);
PAINT ORANGE (-500 3625);
DISPLAY INVISIBLE (-500 3625);
FORCEPROP 1 LAST OFFPAGE TRUE
J 0
(25 3450);
DISPLAY 1.404255 (25 3450);
PAINT GREEN (25 3450);
DISPLAY INVISIBLE (25 3450);
FORCEPROP 1 LAST COMMENT_BODY TRUE
J 0
(-175 3475);
DISPLAY 1.404255 (-175 3475);
PAINT PEACH (-175 3475);
DISPLAY INVISIBLE (-175 3475);
FORCEADD OFFPAGE..1
(-300 3500);
FORCEPROP 2 LAST $XR2 112 
J 0
(-731 3500);
DISPLAY 0.638298 (-731 3500);
PAINT MONO (-731 3500);
FORCEPROP 2 LAST $XR1 55 
J 0
(-611 3500);
DISPLAY 0.638298 (-611 3500);
PAINT MONO (-611 3500);
FORCEPROP 2 LAST $XR0 21 
J 0
(-521 3500);
DISPLAY 0.638298 (-521 3500);
PAINT MONO (-521 3500);
FORCEPROP 2 LAST CDS_LIB mstr_standard
J 0
(-300 3500);
DISPLAY 2.212766 (-300 3500);
PAINT ORANGE (-300 3500);
DISPLAY INVISIBLE (-300 3500);
FORCEPROP 2 LAST PATH I83
J 0
(-500 3550);
DISPLAY 1.021277 (-500 3550);
PAINT ORANGE (-500 3550);
DISPLAY INVISIBLE (-500 3550);
FORCEPROP 1 LAST OFFPAGE TRUE
J 0
(25 3375);
DISPLAY 1.404255 (25 3375);
PAINT GREEN (25 3375);
DISPLAY INVISIBLE (25 3375);
FORCEPROP 1 LAST COMMENT_BODY TRUE
J 0
(-175 3400);
DISPLAY 1.404255 (-175 3400);
PAINT PEACH (-175 3400);
DISPLAY INVISIBLE (-175 3400);
FORCEADD OFFPAGE..1
(-300 3425);
FORCEPROP 2 LAST $XR2 112 
J 0
(-731 3425);
DISPLAY 0.638298 (-731 3425);
PAINT MONO (-731 3425);
FORCEPROP 2 LAST $XR1 55 
J 0
(-611 3425);
DISPLAY 0.638298 (-611 3425);
PAINT MONO (-611 3425);
FORCEPROP 2 LAST $XR0 21 
J 0
(-521 3425);
DISPLAY 0.638298 (-521 3425);
PAINT MONO (-521 3425);
FORCEPROP 2 LAST CDS_LIB mstr_standard
J 0
(-300 3425);
DISPLAY 2.212766 (-300 3425);
PAINT ORANGE (-300 3425);
DISPLAY INVISIBLE (-300 3425);
FORCEPROP 2 LAST PATH I84
J 0
(-500 3475);
DISPLAY 1.021277 (-500 3475);
PAINT ORANGE (-500 3475);
DISPLAY INVISIBLE (-500 3475);
FORCEPROP 1 LAST OFFPAGE TRUE
J 0
(25 3300);
DISPLAY 1.404255 (25 3300);
PAINT GREEN (25 3300);
DISPLAY INVISIBLE (25 3300);
FORCEPROP 1 LAST COMMENT_BODY TRUE
J 0
(-175 3325);
DISPLAY 1.404255 (-175 3325);
PAINT PEACH (-175 3325);
DISPLAY INVISIBLE (-175 3325);
FORCEADD RES..2
(-1950 3600);
FORCEPROP 1 LAST PART_NUMBER G21796-026
J 0
(-1910 3475);
DISPLAY 0.617021 (-1910 3475);
PAINT BLUE (-1910 3475);
FORCEPROP 1 LAST VALUE 1.00K
J 0
(-1905 3675);
DISPLAY 0.617021 (-1905 3675);
PAINT SKYBLUE (-1905 3675);
FORCEPROP 1 LAST TOLERANCE 1%
J 0
(-1905 3625);
DISPLAY 0.617021 (-1905 3625);
PAINT SKYBLUE (-1905 3625);
FORCEPROP 1 LAST PACK_TYPE 0402
J 0
(-1910 3425);
DISPLAY 0.617021 (-1910 3425);
PAINT SKYBLUE (-1910 3425);
FORCEPROP 1 LAST MATERIAL CHIP
J 0
(-1910 3525);
DISPLAY 0.617021 (-1910 3525);
PAINT SKYBLUE (-1910 3525);
FORCEPROP 1 LAST WATTAGE 1/16W
J 0
(-1910 3575);
DISPLAY 0.617021 (-1910 3575);
PAINT SKYBLUE (-1910 3575);
FORCEPROP 1 LASTPIN (-1950 3500) $PN 2
J 0
(-1945 3510);
DISPLAY 0.617021 (-1945 3510);
PAINT ORANGE (-1945 3510);
FORCEPROP 1 LASTPIN (-1950 3700) $PN 1
J 0
(-1945 3662);
DISPLAY 0.617021 (-1945 3662);
PAINT ORANGE (-1945 3662);
FORCEPROP 1 LAST LOCATION R3M10
J 0
(-1905 3725);
DISPLAY 0.617021 (-1905 3725);
PAINT AQUA (-1905 3725);
FORCEPROP 2 LAST SEC_TYPE 0402
J 0
(-1900 3825);
DISPLAY 1.021277 (-1900 3825);
PAINT ORANGE (-1900 3825);
DISPLAY INVISIBLE (-1900 3825);
FORCEPROP 2 LAST CDS_LIB mstr_discrete
J 0
(-1950 3600);
PAINT ORANGE (-1950 3600);
DISPLAY INVISIBLE (-1950 3600);
FORCEPROP 2 LAST BOM_COST DEBUG
J 0
(-1900 3775);
DISPLAY 1.617021 (-1900 3775);
PAINT WHITE (-1900 3775);
DISPLAY INVISIBLE (-1900 3775);
FORCEPROP 2 LAST SEC 1
J 0
(-1900 3825);
DISPLAY 0.680851 (-1900 3825);
PAINT MONO (-1900 3825);
DISPLAY INVISIBLE (-1900 3825);
FORCEPROP 2 LAST CDS_LOCATION R3M10
J 0
(-1905 3725);
DISPLAY 0.617021 (-1905 3725);
PAINT AQUA (-1905 3725);
DISPLAY INVISIBLE (-1905 3725);
FORCEPROP 1 LAST PATH I85
J 0
(-1900 3775);
DISPLAY 0.978723 (-1900 3775);
PAINT WHITE (-1900 3775);
DISPLAY INVISIBLE (-1900 3775);
FORCEPROP 2 LAST ROOM DEBUG
J 0
(-1900 3775);
DISPLAY 1.617021 (-1900 3775);
PAINT WHITE (-1900 3775);
DISPLAY INVISIBLE (-1900 3775);
FORCEADD OFFPAGE..5
R 2
(-1225 2775);
FORCEPROP 2 LAST $XR1 112 
J 0
(-946 2775);
DISPLAY 0.638298 (-946 2775);
PAINT MONO (-946 2775);
FORCEPROP 2 LAST $XR0 21 
J 0
(-1036 2775);
DISPLAY 0.638298 (-1036 2775);
PAINT MONO (-1036 2775);
FORCEPROP 2 LAST BOM_COST DEBUG
J 2
(-975 2875);
DISPLAY 1.617021 (-975 2875);
PAINT WHITE (-975 2875);
DISPLAY INVISIBLE (-975 2875);
FORCEPROP 2 LAST ROOM CPU_JTAG_DEBUG
J 2
(-975 2825);
DISPLAY 1.617021 (-975 2825);
PAINT WHITE (-975 2825);
DISPLAY INVISIBLE (-975 2825);
FORCEPROP 2 LAST CDS_LIB mstr_standard
J 0
(-1225 2775);
PAINT ORANGE (-1225 2775);
DISPLAY INVISIBLE (-1225 2775);
FORCEPROP 2 LAST PATH I86
J 0
(-975 2825);
DISPLAY 1.021277 (-975 2825);
PAINT ORANGE (-975 2825);
DISPLAY INVISIBLE (-975 2825);
FORCEPROP 1 LAST OFFPAGE TRUE
J 2
(-1550 2650);
DISPLAY 1.404255 (-1550 2650);
PAINT GREEN (-1550 2650);
DISPLAY INVISIBLE (-1550 2650);
FORCEPROP 1 LAST COMMENT_BODY TRUE
J 2
(-1325 2700);
DISPLAY 1.404255 (-1325 2700);
PAINT PEACH (-1325 2700);
DISPLAY INVISIBLE (-1325 2700);
FORCEADD OFFPAGE..1
R 2
(-1225 2575);
FORCEPROP 2 LAST $XR0 112 
J 0
(-1039 2575);
DISPLAY 0.638298 (-1039 2575);
PAINT MONO (-1039 2575);
FORCEPROP 2 LAST BOM_COST DEBUG
J 2
(-975 2675);
DISPLAY 1.617021 (-975 2675);
PAINT WHITE (-975 2675);
DISPLAY INVISIBLE (-975 2675);
FORCEPROP 2 LAST ROOM CPU_JTAG_DEBUG
J 2
(-975 2625);
DISPLAY 1.617021 (-975 2625);
PAINT WHITE (-975 2625);
DISPLAY INVISIBLE (-975 2625);
FORCEPROP 2 LAST CDS_LIB mstr_standard
J 0
(-1225 2575);
PAINT ORANGE (-1225 2575);
DISPLAY INVISIBLE (-1225 2575);
FORCEPROP 2 LAST PATH I87
J 0
(-925 2625);
DISPLAY 1.021277 (-925 2625);
PAINT ORANGE (-925 2625);
DISPLAY INVISIBLE (-925 2625);
FORCEPROP 1 LAST OFFPAGE TRUE
J 2
(-1550 2450);
DISPLAY 1.404255 (-1550 2450);
PAINT GREEN (-1550 2450);
DISPLAY INVISIBLE (-1550 2450);
FORCEPROP 1 LAST COMMENT_BODY TRUE
J 2
(-1350 2475);
DISPLAY 1.404255 (-1350 2475);
PAINT PEACH (-1350 2475);
DISPLAY INVISIBLE (-1350 2475);
FORCEADD OFFPAGE..5
R 2
(-1225 2375);
FORCEPROP 2 LAST $XR2 112 
J 0
(-856 2375);
DISPLAY 0.638298 (-856 2375);
PAINT MONO (-856 2375);
FORCEPROP 2 LAST $XR1 55 
J 0
(-946 2375);
DISPLAY 0.638298 (-946 2375);
PAINT MONO (-946 2375);
FORCEPROP 2 LAST $XR0 21 
J 0
(-1036 2375);
DISPLAY 0.638298 (-1036 2375);
PAINT MONO (-1036 2375);
FORCEPROP 2 LAST BOM_COST DEBUG
J 2
(-975 2475);
DISPLAY 1.617021 (-975 2475);
PAINT WHITE (-975 2475);
DISPLAY INVISIBLE (-975 2475);
FORCEPROP 2 LAST ROOM CPU_JTAG_DEBUG
J 2
(-975 2425);
DISPLAY 1.617021 (-975 2425);
PAINT WHITE (-975 2425);
DISPLAY INVISIBLE (-975 2425);
FORCEPROP 2 LAST CDS_LIB mstr_standard
J 0
(-1225 2375);
PAINT ORANGE (-1225 2375);
DISPLAY INVISIBLE (-1225 2375);
FORCEPROP 2 LAST PATH I88
J 0
(-875 2425);
DISPLAY 1.021277 (-875 2425);
PAINT ORANGE (-875 2425);
DISPLAY INVISIBLE (-875 2425);
FORCEPROP 1 LAST OFFPAGE TRUE
J 2
(-1550 2250);
DISPLAY 1.404255 (-1550 2250);
PAINT GREEN (-1550 2250);
DISPLAY INVISIBLE (-1550 2250);
FORCEPROP 1 LAST COMMENT_BODY TRUE
J 2
(-1325 2300);
DISPLAY 1.404255 (-1325 2300);
PAINT PEACH (-1325 2300);
DISPLAY INVISIBLE (-1325 2300);
FORCEADD OFFPAGE..5
R 2
(-1225 2175);
FORCEPROP 2 LAST $XR2 112 
J 0
(-856 2175);
DISPLAY 0.638298 (-856 2175);
PAINT MONO (-856 2175);
FORCEPROP 2 LAST $XR1 55 
J 0
(-946 2175);
DISPLAY 0.638298 (-946 2175);
PAINT MONO (-946 2175);
FORCEPROP 2 LAST $XR0 21 
J 0
(-1036 2175);
DISPLAY 0.638298 (-1036 2175);
PAINT MONO (-1036 2175);
FORCEPROP 2 LAST BOM_COST DEBUG
J 2
(-975 2275);
DISPLAY 1.617021 (-975 2275);
PAINT WHITE (-975 2275);
DISPLAY INVISIBLE (-975 2275);
FORCEPROP 2 LAST ROOM CPU_JTAG_DEBUG
J 2
(-975 2225);
DISPLAY 1.617021 (-975 2225);
PAINT WHITE (-975 2225);
DISPLAY INVISIBLE (-975 2225);
FORCEPROP 2 LAST CDS_LIB mstr_standard
J 0
(-1225 2175);
PAINT ORANGE (-1225 2175);
DISPLAY INVISIBLE (-1225 2175);
FORCEPROP 2 LAST PATH I89
J 0
(-875 2225);
DISPLAY 1.021277 (-875 2225);
PAINT ORANGE (-875 2225);
DISPLAY INVISIBLE (-875 2225);
FORCEPROP 1 LAST OFFPAGE TRUE
J 2
(-1550 2050);
DISPLAY 1.404255 (-1550 2050);
PAINT GREEN (-1550 2050);
DISPLAY INVISIBLE (-1550 2050);
FORCEPROP 1 LAST COMMENT_BODY TRUE
J 2
(-1325 2100);
DISPLAY 1.404255 (-1325 2100);
PAINT PEACH (-1325 2100);
DISPLAY INVISIBLE (-1325 2100);
FORCEADD OFFPAGE..5
R 2
(-1225 1550);
FORCEPROP 2 LAST $XR2 112 
J 0
(-856 1550);
DISPLAY 0.638298 (-856 1550);
PAINT MONO (-856 1550);
FORCEPROP 2 LAST $XR1 55 
J 0
(-946 1550);
DISPLAY 0.638298 (-946 1550);
PAINT MONO (-946 1550);
FORCEPROP 2 LAST $XR0 21 
J 0
(-1036 1550);
DISPLAY 0.638298 (-1036 1550);
PAINT MONO (-1036 1550);
FORCEPROP 2 LAST BOM_COST DEBUG
J 2
(-975 1650);
DISPLAY 1.617021 (-975 1650);
PAINT WHITE (-975 1650);
DISPLAY INVISIBLE (-975 1650);
FORCEPROP 2 LAST ROOM CPU_JTAG_DEBUG
J 2
(-975 1600);
DISPLAY 1.617021 (-975 1600);
PAINT WHITE (-975 1600);
DISPLAY INVISIBLE (-975 1600);
FORCEPROP 2 LAST CDS_LIB mstr_standard
J 0
(-1225 1550);
PAINT ORANGE (-1225 1550);
DISPLAY INVISIBLE (-1225 1550);
FORCEPROP 2 LAST PATH I90
J 0
(-875 1600);
DISPLAY 1.021277 (-875 1600);
PAINT ORANGE (-875 1600);
DISPLAY INVISIBLE (-875 1600);
FORCEPROP 1 LAST OFFPAGE TRUE
J 2
(-1550 1425);
DISPLAY 1.404255 (-1550 1425);
PAINT GREEN (-1550 1425);
DISPLAY INVISIBLE (-1550 1425);
FORCEPROP 1 LAST COMMENT_BODY TRUE
J 2
(-1325 1475);
DISPLAY 1.404255 (-1325 1475);
PAINT PEACH (-1325 1475);
DISPLAY INVISIBLE (-1325 1475);
FORCEADD OFFPAGE..1
R 2
(-1225 1350);
FORCEPROP 2 LAST $XR2 112 
J 0
(-859 1350);
DISPLAY 0.638298 (-859 1350);
PAINT MONO (-859 1350);
FORCEPROP 2 LAST $XR1 55 
J 0
(-949 1350);
DISPLAY 0.638298 (-949 1350);
PAINT MONO (-949 1350);
FORCEPROP 2 LAST $XR0 21 
J 0
(-1039 1350);
DISPLAY 0.638298 (-1039 1350);
PAINT MONO (-1039 1350);
FORCEPROP 2 LAST BOM_COST DEBUG
J 2
(-975 1450);
DISPLAY 1.617021 (-975 1450);
PAINT WHITE (-975 1450);
DISPLAY INVISIBLE (-975 1450);
FORCEPROP 2 LAST ROOM CPU_JTAG_DEBUG
J 2
(-975 1400);
DISPLAY 1.617021 (-975 1400);
PAINT WHITE (-975 1400);
DISPLAY INVISIBLE (-975 1400);
FORCEPROP 2 LAST CDS_LIB mstr_standard
J 0
(-1225 1350);
PAINT ORANGE (-1225 1350);
DISPLAY INVISIBLE (-1225 1350);
FORCEPROP 2 LAST PATH I91
J 0
(-875 1400);
DISPLAY 1.021277 (-875 1400);
PAINT ORANGE (-875 1400);
DISPLAY INVISIBLE (-875 1400);
FORCEPROP 1 LAST OFFPAGE TRUE
J 2
(-1550 1225);
DISPLAY 1.404255 (-1550 1225);
PAINT GREEN (-1550 1225);
DISPLAY INVISIBLE (-1550 1225);
FORCEPROP 1 LAST COMMENT_BODY TRUE
J 2
(-1350 1250);
DISPLAY 1.404255 (-1350 1250);
PAINT PEACH (-1350 1250);
DISPLAY INVISIBLE (-1350 1250);
FORCEADD OFFPAGE..5
R 2
(-1225 1150);
FORCEPROP 2 LAST $XR2 112 
J 0
(-856 1150);
DISPLAY 0.638298 (-856 1150);
PAINT MONO (-856 1150);
FORCEPROP 2 LAST $XR1 55 
J 0
(-946 1150);
DISPLAY 0.638298 (-946 1150);
PAINT MONO (-946 1150);
FORCEPROP 2 LAST $XR0 21 
J 0
(-1036 1150);
DISPLAY 0.638298 (-1036 1150);
PAINT MONO (-1036 1150);
FORCEPROP 2 LAST BOM_COST DEBUG
J 2
(-975 1250);
DISPLAY 1.617021 (-975 1250);
PAINT WHITE (-975 1250);
DISPLAY INVISIBLE (-975 1250);
FORCEPROP 2 LAST ROOM CPU_JTAG_DEBUG
J 2
(-975 1200);
DISPLAY 1.617021 (-975 1200);
PAINT WHITE (-975 1200);
DISPLAY INVISIBLE (-975 1200);
FORCEPROP 2 LAST CDS_LIB mstr_standard
J 0
(-1225 1150);
PAINT ORANGE (-1225 1150);
DISPLAY INVISIBLE (-1225 1150);
FORCEPROP 2 LAST PATH I92
J 0
(-875 1200);
DISPLAY 1.021277 (-875 1200);
PAINT ORANGE (-875 1200);
DISPLAY INVISIBLE (-875 1200);
FORCEPROP 1 LAST OFFPAGE TRUE
J 2
(-1550 1025);
DISPLAY 1.404255 (-1550 1025);
PAINT GREEN (-1550 1025);
DISPLAY INVISIBLE (-1550 1025);
FORCEPROP 1 LAST COMMENT_BODY TRUE
J 2
(-1325 1075);
DISPLAY 1.404255 (-1325 1075);
PAINT PEACH (-1325 1075);
DISPLAY INVISIBLE (-1325 1075);
FORCEADD OFFPAGE..5
R 2
(-1225 950);
FORCEPROP 2 LAST $XR2 112 
J 0
(-856 950);
DISPLAY 0.638298 (-856 950);
PAINT MONO (-856 950);
FORCEPROP 2 LAST $XR1 55 
J 0
(-946 950);
DISPLAY 0.638298 (-946 950);
PAINT MONO (-946 950);
FORCEPROP 2 LAST $XR0 21 
J 0
(-1036 950);
DISPLAY 0.638298 (-1036 950);
PAINT MONO (-1036 950);
FORCEPROP 2 LAST BOM_COST DEBUG
J 2
(-975 1050);
DISPLAY 1.617021 (-975 1050);
PAINT WHITE (-975 1050);
DISPLAY INVISIBLE (-975 1050);
FORCEPROP 2 LAST ROOM CPU_JTAG_DEBUG
J 2
(-975 1000);
DISPLAY 1.617021 (-975 1000);
PAINT WHITE (-975 1000);
DISPLAY INVISIBLE (-975 1000);
FORCEPROP 2 LAST CDS_LIB mstr_standard
J 0
(-1225 950);
PAINT ORANGE (-1225 950);
DISPLAY INVISIBLE (-1225 950);
FORCEPROP 2 LAST PATH I93
J 0
(-875 1000);
DISPLAY 1.021277 (-875 1000);
PAINT ORANGE (-875 1000);
DISPLAY INVISIBLE (-875 1000);
FORCEPROP 1 LAST OFFPAGE TRUE
J 2
(-1550 825);
DISPLAY 1.404255 (-1550 825);
PAINT GREEN (-1550 825);
DISPLAY INVISIBLE (-1550 825);
FORCEPROP 1 LAST COMMENT_BODY TRUE
J 2
(-1325 875);
DISPLAY 1.404255 (-1325 875);
PAINT PEACH (-1325 875);
DISPLAY INVISIBLE (-1325 875);
FORCEADD RES..2
(-2325 3600);
FORCEPROP 1 LAST LOCATION R8B2
J 0
(-2280 3725);
DISPLAY 0.617021 (-2280 3725);
PAINT AQUA (-2280 3725);
FORCEPROP 1 LAST PART_NUMBER G21796-026
J 0
(-2285 3475);
DISPLAY 0.617021 (-2285 3475);
PAINT BLUE (-2285 3475);
FORCEPROP 1 LAST VALUE 1.00K
J 0
(-2280 3675);
DISPLAY 0.617021 (-2280 3675);
PAINT SKYBLUE (-2280 3675);
FORCEPROP 1 LAST TOLERANCE 1%
J 0
(-2280 3625);
DISPLAY 0.617021 (-2280 3625);
PAINT SKYBLUE (-2280 3625);
FORCEPROP 1 LAST PACK_TYPE 0402
J 0
(-2285 3425);
DISPLAY 0.617021 (-2285 3425);
PAINT SKYBLUE (-2285 3425);
FORCEPROP 1 LAST MATERIAL CHIP
J 0
(-2285 3525);
DISPLAY 0.617021 (-2285 3525);
PAINT SKYBLUE (-2285 3525);
FORCEPROP 1 LAST WATTAGE 1/16W
J 0
(-2285 3575);
DISPLAY 0.617021 (-2285 3575);
PAINT SKYBLUE (-2285 3575);
FORCEPROP 1 LASTPIN (-2325 3500) $PN 2
J 0
(-2320 3510);
DISPLAY 0.617021 (-2320 3510);
PAINT ORANGE (-2320 3510);
FORCEPROP 1 LASTPIN (-2325 3700) $PN 1
J 0
(-2320 3662);
DISPLAY 0.617021 (-2320 3662);
PAINT ORANGE (-2320 3662);
FORCEPROP 2 LAST SEC_TYPE 0402
J 0
(-2275 3825);
DISPLAY 1.021277 (-2275 3825);
PAINT ORANGE (-2275 3825);
DISPLAY INVISIBLE (-2275 3825);
FORCEPROP 2 LAST CDS_LIB mstr_discrete
J 0
(-2325 3600);
PAINT ORANGE (-2325 3600);
DISPLAY INVISIBLE (-2325 3600);
FORCEPROP 2 LAST BOM_COST DEBUG
J 0
(-2275 3775);
DISPLAY 1.617021 (-2275 3775);
PAINT WHITE (-2275 3775);
DISPLAY INVISIBLE (-2275 3775);
FORCEPROP 2 LAST SEC 1
J 0
(-2275 3825);
DISPLAY 0.680851 (-2275 3825);
PAINT MONO (-2275 3825);
DISPLAY INVISIBLE (-2275 3825);
FORCEPROP 2 LAST CDS_LOCATION R8B2
J 0
(-2280 3725);
DISPLAY 0.617021 (-2280 3725);
PAINT AQUA (-2280 3725);
DISPLAY INVISIBLE (-2280 3725);
FORCEPROP 1 LAST PATH I94
J 0
(-2275 3775);
DISPLAY 0.978723 (-2275 3775);
PAINT WHITE (-2275 3775);
DISPLAY INVISIBLE (-2275 3775);
FORCEPROP 2 LAST ROOM DEBUG
J 0
(-2275 3775);
DISPLAY 1.617021 (-2275 3775);
PAINT WHITE (-2275 3775);
DISPLAY INVISIBLE (-2275 3775);
FORCEADD RES..2
(-2700 3600);
FORCEPROP 1 LAST PART_NUMBER G21796-208
J 0
(-2660 3475);
DISPLAY 0.617021 (-2660 3475);
PAINT BLUE (-2660 3475);
FORCEPROP 1 LAST VALUE 51.1
J 0
(-2655 3675);
DISPLAY 0.617021 (-2655 3675);
PAINT SKYBLUE (-2655 3675);
FORCEPROP 1 LAST TOLERANCE 1.0%
J 0
(-2655 3625);
DISPLAY 0.617021 (-2655 3625);
PAINT SKYBLUE (-2655 3625);
FORCEPROP 1 LAST PACK_TYPE 0402
J 0
(-2660 3425);
DISPLAY 0.617021 (-2660 3425);
PAINT SKYBLUE (-2660 3425);
FORCEPROP 1 LAST MATERIAL CHIP
J 0
(-2660 3525);
DISPLAY 0.617021 (-2660 3525);
PAINT SKYBLUE (-2660 3525);
FORCEPROP 1 LAST WATTAGE 1/16W
J 0
(-2660 3575);
DISPLAY 0.617021 (-2660 3575);
PAINT SKYBLUE (-2660 3575);
FORCEPROP 1 LASTPIN (-2700 3500) $PN 2
J 0
(-2695 3510);
DISPLAY 0.617021 (-2695 3510);
PAINT WHITE (-2695 3510);
FORCEPROP 1 LASTPIN (-2700 3700) $PN 1
J 0
(-2695 3662);
DISPLAY 0.617021 (-2695 3662);
PAINT WHITE (-2695 3662);
FORCEPROP 1 LAST LOCATION R8B1
J 0
(-2655 3725);
DISPLAY 0.617021 (-2655 3725);
PAINT AQUA (-2655 3725);
FORCEPROP 2 LAST BOM_COST DEBUG
J 0
(-2650 3775);
DISPLAY 1.617021 (-2650 3775);
PAINT WHITE (-2650 3775);
DISPLAY INVISIBLE (-2650 3775);
FORCEPROP 2 LAST CDS_LIB mstr_discrete
J 0
(-2700 3600);
DISPLAY 2.212766 (-2700 3600);
PAINT ORANGE (-2700 3600);
DISPLAY INVISIBLE (-2700 3600);
FORCEPROP 2 LAST CDS_SEC 1
J 0
(-2650 3825);
PAINT MONO (-2650 3825);
DISPLAY INVISIBLE (-2650 3825);
FORCEPROP 2 LAST $SEC 1
J 0
(-2650 3825);
PAINT MONO (-2650 3825);
DISPLAY INVISIBLE (-2650 3825);
FORCEPROP 2 LAST CDS_LOCATION R8B1
J 0
(-2655 3725);
DISPLAY 0.617021 (-2655 3725);
PAINT AQUA (-2655 3725);
DISPLAY INVISIBLE (-2655 3725);
FORCEPROP 1 LAST PATH I95
J 0
(-2650 3775);
DISPLAY 0.978723 (-2650 3775);
PAINT WHITE (-2650 3775);
DISPLAY INVISIBLE (-2650 3775);
FORCEPROP 2 LAST ROOM DEBUG
J 0
(-2650 3775);
DISPLAY 1.617021 (-2650 3775);
PAINT WHITE (-2650 3775);
DISPLAY INVISIBLE (-2650 3775);
FORCEADD GND..1
(-2700 3300);
FORCEPROP 3 LASTPIN (-2700 3350) SIG_NAME GND\g
J 0
(-2690 3360);
DISPLAY 0.659574 (-2690 3360);
PAINT MONO (-2690 3360);
DISPLAY INVISIBLE (-2690 3360);
FORCEPROP 1 LAST VOLTAGE 0.0V
J 0
(-2745 3257);
DISPLAY 0.340426 (-2745 3257);
PAINT SKYBLUE (-2745 3257);
DISPLAY INVISIBLE (-2745 3257);
FORCEPROP 1 LAST SIZE 1B
J 0
(-2625 3250);
DISPLAY 2.382979 (-2625 3250);
PAINT GREEN (-2625 3250);
DISPLAY INVISIBLE (-2625 3250);
FORCEPROP 2 LAST CDS_LIB mstr_symbols
J 0
(-2700 3300);
DISPLAY 2.212766 (-2700 3300);
PAINT ORANGE (-2700 3300);
DISPLAY INVISIBLE (-2700 3300);
FORCEPROP 1 LAST PATH I96
J 0
(-2625 3300);
DISPLAY 0.872340 (-2625 3300);
PAINT AQUA (-2625 3300);
DISPLAY INVISIBLE (-2625 3300);
FORCEPROP 1 LAST BODY_TYPE PLUMBING
J 0
(-2745 3257);
DISPLAY 0.340426 (-2745 3257);
PAINT GREEN (-2745 3257);
DISPLAY INVISIBLE (-2745 3257);
FORCEPROP 1 LAST HDL_POWER GND
J 0
(-2700 3450);
PAINT GREEN (-2700 3450);
DISPLAY INVISIBLE (-2700 3450);
FORCEADD OFFPAGE..1
(-3200 4250);
FORCEPROP 2 LAST $XR3 112 
J 0
(-3482 4214);
DISPLAY 0.638298 (-3482 4214);
PAINT MONO (-3482 4214);
FORCEPROP 2 LAST $XR2 254 
J 0
(-3722 4250);
DISPLAY 0.638298 (-3722 4250);
PAINT MONO (-3722 4250);
FORCEPROP 2 LAST $XR1 118 
J 0
(-3602 4250);
DISPLAY 0.638298 (-3602 4250);
PAINT MONO (-3602 4250);
FORCEPROP 2 LAST $XR0 111 
J 0
(-3482 4250);
DISPLAY 0.638298 (-3482 4250);
PAINT MONO (-3482 4250);
FORCEPROP 2 LAST CDS_LIB mstr_standard
J 0
(-3200 4250);
DISPLAY 2.212766 (-3200 4250);
PAINT ORANGE (-3200 4250);
DISPLAY INVISIBLE (-3200 4250);
FORCEPROP 2 LAST PATH I97
J 0
(-3450 4300);
DISPLAY 1.021277 (-3450 4300);
PAINT ORANGE (-3450 4300);
DISPLAY INVISIBLE (-3450 4300);
FORCEPROP 1 LAST OFFPAGE TRUE
J 0
(-2875 4125);
DISPLAY 1.404255 (-2875 4125);
PAINT GREEN (-2875 4125);
DISPLAY INVISIBLE (-2875 4125);
FORCEPROP 1 LAST COMMENT_BODY TRUE
J 0
(-3075 4150);
DISPLAY 1.404255 (-3075 4150);
PAINT PEACH (-3075 4150);
DISPLAY INVISIBLE (-3075 4150);
FORCEADD OFFPAGE..1
(-3200 4175);
FORCEPROP 2 LAST $XR3 112 
J 0
(-3482 4139);
DISPLAY 0.638298 (-3482 4139);
PAINT MONO (-3482 4139);
FORCEPROP 2 LAST $XR2 254 
J 0
(-3722 4175);
DISPLAY 0.638298 (-3722 4175);
PAINT MONO (-3722 4175);
FORCEPROP 2 LAST $XR1 118 
J 0
(-3602 4175);
DISPLAY 0.638298 (-3602 4175);
PAINT MONO (-3602 4175);
FORCEPROP 2 LAST $XR0 111 
J 0
(-3482 4175);
DISPLAY 0.638298 (-3482 4175);
PAINT MONO (-3482 4175);
FORCEPROP 2 LAST CDS_LIB mstr_standard
J 0
(-3200 4175);
DISPLAY 2.212766 (-3200 4175);
PAINT ORANGE (-3200 4175);
DISPLAY INVISIBLE (-3200 4175);
FORCEPROP 2 LAST PATH I98
J 0
(-3450 4225);
DISPLAY 1.021277 (-3450 4225);
PAINT ORANGE (-3450 4225);
DISPLAY INVISIBLE (-3450 4225);
FORCEPROP 1 LAST OFFPAGE TRUE
J 0
(-2875 4050);
DISPLAY 1.404255 (-2875 4050);
PAINT GREEN (-2875 4050);
DISPLAY INVISIBLE (-2875 4050);
FORCEPROP 1 LAST COMMENT_BODY TRUE
J 0
(-3075 4075);
DISPLAY 1.404255 (-3075 4075);
PAINT PEACH (-3075 4075);
DISPLAY INVISIBLE (-3075 4075);
FORCEADD OFFPAGE..1
(-3200 4100);
FORCEPROP 2 LAST $XR3 255 
J 0
(-3482 4064);
DISPLAY 0.638298 (-3482 4064);
PAINT MONO (-3482 4064);
FORCEPROP 2 LAST $XR2 111 
J 0
(-3722 4100);
DISPLAY 0.638298 (-3722 4100);
PAINT MONO (-3722 4100);
FORCEPROP 2 LAST $XR1 118 
J 0
(-3602 4100);
DISPLAY 0.638298 (-3602 4100);
PAINT MONO (-3602 4100);
FORCEPROP 2 LAST $XR0 112 
J 0
(-3482 4100);
DISPLAY 0.638298 (-3482 4100);
PAINT MONO (-3482 4100);
FORCEPROP 2 LAST CDS_LIB mstr_standard
J 0
(-3200 4100);
DISPLAY 2.212766 (-3200 4100);
PAINT ORANGE (-3200 4100);
DISPLAY INVISIBLE (-3200 4100);
FORCEPROP 2 LAST PATH I99
J 0
(-3450 4150);
DISPLAY 1.021277 (-3450 4150);
PAINT ORANGE (-3450 4150);
DISPLAY INVISIBLE (-3450 4150);
FORCEPROP 1 LAST OFFPAGE TRUE
J 0
(-2875 3975);
DISPLAY 1.404255 (-2875 3975);
PAINT GREEN (-2875 3975);
DISPLAY INVISIBLE (-2875 3975);
FORCEPROP 1 LAST COMMENT_BODY TRUE
J 0
(-3075 4000);
DISPLAY 1.404255 (-3075 4000);
PAINT PEACH (-3075 4000);
DISPLAY INVISIBLE (-3075 4000);
FORCEADD CAD_NOTE..1
(2375 2950);
FORCEPROP 0 LAST L1 PLACE PULL-UP RESISTORS WITHIN 1.5'' OF CPU1
J 0
(2250 2825);
DISPLAY 0.744681 (2250 2825);
PAINT WHITE (2250 2825);
FORCEPROP 2 LAST CDS_LIB mstr_symbols
J 0
(2375 2950);
PAINT ORANGE (2375 2950);
DISPLAY INVISIBLE (2375 2950);
FORCEPROP 1 LAST COMMENT_BODY TRUE
J 0
(2400 3050);
DISPLAY 2.212766 (2400 3050);
PAINT PEACH (2400 3050);
DISPLAY INVISIBLE (2400 3050);
FORCEADD CAD_NOTE..1
(-1825 600);
FORCEPROP 0 LAST L1 PLACE CAP NEXT TO FET SWITCH
J 0
(-1975 475);
DISPLAY 0.595745 (-1975 475);
PAINT WHITE (-1975 475);
FORCEPROP 2 LAST CDS_LIB mstr_symbols
J 0
(-1825 600);
PAINT MONO (-1825 600);
DISPLAY INVISIBLE (-1825 600);
FORCEPROP 1 LAST COMMENT_BODY TRUE
J 0
(-1800 700);
DISPLAY 2.212766 (-1800 700);
PAINT PEACH (-1800 700);
DISPLAY INVISIBLE (-1800 700);
FORCEADD CAD_NOTE..1
(-550 4450);
FORCEPROP 0 LAST L1 PLACE PULL-UP RESISTORS WITHIN 1.5'' OF CPU0
J 0
(-675 4325);
DISPLAY 0.744681 (-675 4325);
PAINT WHITE (-675 4325);
FORCEPROP 2 LAST CDS_LIB mstr_symbols
J 0
(-550 4450);
PAINT MONO (-550 4450);
DISPLAY INVISIBLE (-550 4450);
FORCEPROP 1 LAST COMMENT_BODY TRUE
J 0
(-525 4550);
DISPLAY 2.212766 (-525 4550);
PAINT PEACH (-525 4550);
DISPLAY INVISIBLE (-525 4550);
FORCEADD CAD_NOTE..1
(3825 3850);
FORCEPROP 2 LAST CDS_LIB mstr_symbols
J 0
(3825 3850);
PAINT MONO (3825 3850);
DISPLAY INVISIBLE (3825 3850);
FORCEPROP 1 LAST COMMENT_BODY TRUE
J 0
(3850 3950);
DISPLAY 2.212766 (3850 3950);
PAINT PEACH (3850 3950);
DISPLAY INVISIBLE (3850 3950);
FORCEADD CAD_NOTE..1
(-1675 1975);
FORCEPROP 0 LAST L1 PLACE CAP NEXT TO FET SWITCH
J 0
(-1825 1850);
DISPLAY 0.595745 (-1825 1850);
PAINT WHITE (-1825 1850);
FORCEPROP 2 LAST CDS_LIB mstr_symbols
J 0
(-1675 1975);
PAINT MONO (-1675 1975);
DISPLAY INVISIBLE (-1675 1975);
FORCEPROP 1 LAST COMMENT_BODY TRUE
J 0
(-1650 2075);
DISPLAY 2.212766 (-1650 2075);
PAINT PEACH (-1650 2075);
DISPLAY INVISIBLE (-1650 2075);
FORCEADD CAD_NOTE..1
(1250 1200);
FORCEPROP 0 LAST L1 PLACE PD RESISTORS WITHIN 1.1'' OF CPU PACKAGE
J 0
(1125 1075);
DISPLAY 0.744681 (1125 1075);
PAINT WHITE (1125 1075);
FORCEPROP 2 LAST CDS_LIB mstr_symbols
J 0
(1250 1200);
PAINT ORANGE (1250 1200);
DISPLAY INVISIBLE (1250 1200);
FORCEPROP 1 LAST COMMENT_BODY TRUE
J 0
(1275 1300);
DISPLAY 2.212766 (1275 1300);
PAINT PEACH (1275 1300);
DISPLAY INVISIBLE (1275 1300);
FORCEADD CAD_NOTE..1
(-3475 3325);
FORCEPROP 0 LAST L1 PLACE PULL-DOWN RESISTORS WITHIN 1.1'' OF PCH
J 0
(-3625 3200);
DISPLAY 0.744681 (-3625 3200);
PAINT WHITE (-3625 3200);
FORCEPROP 2 LAST CDS_LIB mstr_symbols
J 0
(-3475 3325);
PAINT MONO (-3475 3325);
DISPLAY INVISIBLE (-3475 3325);
FORCEPROP 1 LAST COMMENT_BODY TRUE
J 0
(-3450 3425);
DISPLAY 2.212766 (-3450 3425);
PAINT PEACH (-3450 3425);
DISPLAY INVISIBLE (-3450 3425);
FORCEADD CAD_NOTE..1
(-3525 4800);
FORCEPROP 0 LAST L1 PLACE PULL-UP RESISTORS WITHIN 1.5'' OF PCH
J 0
(-3650 4675);
DISPLAY 0.744681 (-3650 4675);
PAINT WHITE (-3650 4675);
FORCEPROP 2 LAST CDS_LIB mstr_symbols
J 0
(-3525 4800);
PAINT MONO (-3525 4800);
DISPLAY INVISIBLE (-3525 4800);
FORCEPROP 1 LAST COMMENT_BODY TRUE
J 0
(-3500 4900);
DISPLAY 2.212766 (-3500 4900);
PAINT PEACH (-3500 4900);
DISPLAY INVISIBLE (-3500 4900);
FORCEADD INTEL_CORP_BPAGE..1
(4250 200);
FORCEPROP 1 LAST CDS_CON_LAST_MODIFIED Fri Jun 16 17:48:44 2017
J 0
(2825 525);
PAINT ORANGE (2825 525);
DISPLAY INVISIBLE (2825 525);
FORCEPROP 1 LAST CUSTOM_TXT_CDS <CURRENT_DESIGN_SHEET> OF <TOTAL_DESIGN_SHEETS>
J 0
(3750 225);
PAINT ORANGE (3750 225);
FORCEPROP 1 LAST CUSTOM_TXT_CDS <CON_LAST_MODIFIED>
J 0
(250 300);
PAINT ORANGE (250 300);
FORCEPROP 2 LAST CUSTOM_TXT_CDS <XR_PAGE_TITLE>
J 0
(-3640 5450);
DISPLAY 0.638298 (-3640 5450);
PAINT PINK (-3640 5450);
DISPLAY INVISIBLE (-3640 5450);
FORCEPROP 1 LAST SCH_TITLE CPU & PCH XDP (2-2)
J 0
(-3700 250);
DISPLAY 1.212766 (-3700 250);
PAINT YELLOW (-3700 250);
FORCEPROP 2 LAST PAGE_BORDER TRUE
J 0
(-3640 5450);
DISPLAY 0.638298 (-3640 5450);
PAINT PINK (-3640 5450);
DISPLAY INVISIBLE (-3640 5450);
FORCEPROP 2 LAST CDS_LIB mstr_symbols
J 0
(4250 200);
PAINT MONO (4250 200);
DISPLAY INVISIBLE (4250 200);
FORCEPROP 1 LAST COMMENT_BODY TRUE
J 0
(4262 212);
DISPLAY 0.468085 (4262 212);
PAINT PEACH (4262 212);
DISPLAY INVISIBLE (4262 212);
FORCEPROP 2 LAST CDS_XR_PAGE_TITLE CR-112 : @BASEBOARD_FAB2_LIB.BASEBOARD_FAB2(SCH_1):PAGE112
J 0
(-3640 5450);
DISPLAY 0.638298 (-3640 5450);
PAINT PINK (-3640 5450);
DISPLAY INVISIBLE (-3640 5450);
WIRE 16 -1 (3500 2650)(3500 2600);
WIRE 16 -1 (3175 2600)(3500 2600);
WIRE 16 -1 (3500 2600)(3500 2500);
WIRE 16 -1 (3175 2500)(3175 2600);
WIRE 16 -1 (1950 2675)(1950 2625);
WIRE 16 -1 (1950 2625)(1600 2625);
WIRE 16 -1 (1950 2625)(1950 2500);
WIRE 16 -1 (1600 2500)(1600 2625);
WIRE 16 -1 (-1200 4700)(-1200 4650);
WIRE 16 -1 (-1200 4650)(-1575 4650);
WIRE 16 -1 (-1200 4650)(-1200 4525);
WIRE 16 -1 (-1575 4650)(-1950 4650);
WIRE 16 -1 (-1575 4525)(-1575 4650);
WIRE 16 -1 (-1950 4650)(-2325 4650);
WIRE 16 -1 (-1950 4650)(-1950 4525);
WIRE 16 -1 (-2325 4650)(-2700 4650);
WIRE 16 -1 (-2325 4525)(-2325 4650);
WIRE 16 -1 (-2700 4525)(-2700 4650);
WIRE 16 -1 (3550 3625)(3550 3575);
WIRE 16 -1 (500 2500)(500 2625);
WIRE 16 -1 (1225 2625)(1225 2575);
WIRE 16 -1 (1225 2575)(875 2575);
WIRE 16 -1 (1225 2575)(1225 2500);
WIRE 16 -1 (875 2500)(875 2575);
WIRE 16 -1 (-1125 1750)(-1125 1725);
WIRE 16 -1 (-1350 525)(-1350 500);
WIRE 16 -1 (3550 3875)(3550 3825);
WIRE 16 -1 (2700 4250)(2700 4200);
WIRE 16 -1 (2700 4200)(3100 4200);
WIRE 16 -1 (2700 4125)(2700 4200);
WIRE 16 -1 (3100 4525)(3100 4200);
WIRE 16 -1 (3100 4125)(3100 4200);
WIRE 16 -1 (2950 4525)(3100 4525);
WIRE 16 -1 (2675 2650)(2675 2625);
WIRE 16 -1 (2675 2625)(2325 2625);
WIRE 16 -1 (2675 2500)(2675 2625);
WIRE 16 -1 (2325 2500)(2325 2625);
WIRE 16 -1 (-1125 2000)(-1125 1950);
WIRE 16 -1 (-1350 750)(-1350 725);
WIRE 16 -1 (2175 4525)(2175 4500);
WIRE 16 -1 (2250 4525)(2175 4525);
WIRE 16 -1 (2700 3725)(2700 3750);
WIRE 16 -1 (2700 3750)(3100 3750);
WIRE 16 -1 (2700 3925)(2700 3750);
WIRE 16 -1 (3100 3750)(3100 3925);
WIRE 16 -1 (1175 4100)(1175 4025);
WIRE 16 -1 (1175 4025)(875 4025);
WIRE 16 -1 (1175 4025)(1175 3900);
WIRE 16 -1 (875 4025)(575 4025);
WIRE 16 -1 (875 3925)(875 4025);
WIRE 16 -1 (275 4025)(575 4025);
WIRE 16 -1 (575 4025)(575 3900);
WIRE 16 -1 (275 3900)(275 4025);
WIRE 16 -1 (500 775)(500 850);
WIRE 16 -1 (875 850)(500 850);
WIRE 16 -1 (500 1000)(500 850);
WIRE 16 -1 (875 1000)(875 850);
WIRE 16 -1 (-2700 3350)(-2700 3400);
WIRE 16 -1 (-2325 3400)(-2700 3400);
WIRE 16 -1 (-2700 3400)(-2700 3500);
WIRE 16 -1 (-1950 3400)(-2325 3400);
WIRE 16 -1 (-2325 3500)(-2325 3400);
WIRE 16 -1 (-1950 3500)(-1950 3400);
WIRE 16 -1 (-3600 5125)(-3600 4875);
WIRE 16 -1 (-1950 4875)(-3600 4875);
WIRE 16 -1 (-1950 5125)(-3600 5125);
WIRE 16 -1 (-1950 5125)(-1950 4875);
WIRE 16 273 (4200 3150)(-3650 3150);
WIRE 16 -1 (3500 2300)(3500 1500);
WIRE 16 -1 (-50 1500)(3500 1500);
FORCEPROP 2 LAST SIG_NAME XDP_CPU_OBSFN_B1_MBP7_N
J 0
(-10 1510);
DISPLAY 0.617021 (-10 1510);
PAINT ORANGE (-10 1510);
WIRE 16 -1 (-1975 5100)(-3575 5100);
WIRE 16 -1 (-1975 5100)(-1975 4900);
WIRE 16 -1 (-3575 5100)(-3575 4900);
WIRE 16 -1 (-3575 4900)(-1975 4900);
WIRE 16 -1 (-150 3000)(-150 2800);
WIRE 16 -1 (-150 2800)(1450 2800);
WIRE 16 -1 (1450 3000)(-150 3000);
WIRE 16 -1 (1450 3000)(1450 2800);
WIRE 16 -1 (-1950 3875)(-3150 3875);
FORCEPROP 2 LAST SIG_NAME XDP_PCH_CPU_TCK0
J 0
(-3100 3885);
DISPLAY 0.617021 (-3100 3885);
PAINT ORANGE (-3100 3885);
WIRE 16 -1 (-1950 3700)(-1950 3875);
WIRE 16 -1 (500 1350)(500 1200);
WIRE 16 -1 (-50 1350)(500 1350);
FORCEPROP 2 LAST SIG_NAME XDP_CPU_TRST_N
J 0
(-10 1360);
DISPLAY 0.617021 (-10 1360);
PAINT ORANGE (-10 1360);
WIRE 16 -1 (-2400 1550)(-3125 1550);
FORCEPROP 2 LAST SIG_NAME XDP_PREQ_N
J 0
(-3100 1560);
DISPLAY 0.617021 (-3100 1560);
PAINT ORANGE (-3100 1560);
WIRE 16 -1 (-2400 1350)(-3125 1350);
FORCEPROP 2 LAST SIG_NAME XDP_PRDY_N
J 0
(-3100 1360);
DISPLAY 0.617021 (-3100 1360);
PAINT ORANGE (-3100 1360);
WIRE 16 -1 (-2400 1150)(-3125 1150);
FORCEPROP 2 LAST SIG_NAME XDP_OBSFN_B0_MBP6_N
J 0
(-3100 1160);
DISPLAY 0.617021 (-3100 1160);
PAINT ORANGE (-3100 1160);
WIRE 16 -1 (-2400 950)(-3125 950);
FORCEPROP 2 LAST SIG_NAME XDP_OBSFN_B1_MBP7_N
J 0
(-3100 960);
DISPLAY 0.617021 (-3100 960);
PAINT ORANGE (-3100 960);
WIRE 16 -1 (-3125 850)(-2500 850);
FORCEPROP 2 LAST SIG_NAME PWRGD_PVCCIN_CPU0
J 0
(-3100 868);
DISPLAY 0.617021 (-3100 868);
PAINT ORANGE (-3100 868);
WIRE 16 -1 (-2500 850)(-2400 850);
WIRE 16 -1 (-2500 1050)(-2500 850);
WIRE 16 -1 (-2500 1050)(-2400 1050);
WIRE 16 -1 (-2500 1250)(-2500 1050);
WIRE 16 -1 (-2500 1250)(-2400 1250);
WIRE 16 -1 (-2500 1450)(-2500 1250);
WIRE 16 -1 (-2400 1450)(-2500 1450);
WIRE 16 -1 (-2500 2075)(-2500 1450);
WIRE 16 -1 (-2500 2075)(-2400 2075);
WIRE 16 -1 (-2500 2275)(-2500 2075);
WIRE 16 -1 (-2500 2275)(-2400 2275);
WIRE 16 -1 (-2500 2475)(-2500 2275);
WIRE 16 -1 (-2500 2475)(-2400 2475);
WIRE 16 -1 (-2500 2675)(-2500 2475);
WIRE 16 -1 (-2400 2675)(-2500 2675);
WIRE 16 -1 (-2400 2775)(-3125 2775);
FORCEPROP 2 LAST SIG_NAME XDP_TDI
J 0
(-3085 2785);
DISPLAY 0.617021 (-3085 2785);
PAINT ORANGE (-3085 2785);
WIRE 16 -1 (-2400 2575)(-3125 2575);
FORCEPROP 2 LAST SIG_NAME XDP_TDO
J 0
(-3085 2585);
DISPLAY 0.617021 (-3085 2585);
PAINT ORANGE (-3085 2585);
WIRE 16 -1 (-2400 2375)(-3125 2375);
FORCEPROP 2 LAST SIG_NAME XDP_TMS
J 0
(-3085 2385);
DISPLAY 0.617021 (-3085 2385);
PAINT ORANGE (-3085 2385);
WIRE 16 -1 (-2400 2175)(-3125 2175);
FORCEPROP 2 LAST SIG_NAME XDP_TRST_N
J 0
(-3085 2185);
DISPLAY 0.617021 (-3085 2185);
PAINT ORANGE (-3085 2185);
WIRE 16 -1 (-2700 3725)(-3150 3725);
FORCEPROP 2 LAST SIG_NAME XDP_PCH_TCK1
J 0
(-3100 3735);
DISPLAY 0.617021 (-3100 3735);
PAINT ORANGE (-3100 3735);
WIRE 16 -1 (-2700 3700)(-2700 3725);
WIRE 16 -1 (-3150 3800)(-2325 3800);
FORCEPROP 2 LAST SIG_NAME XDP_TRST_N
J 0
(-3100 3810);
DISPLAY 0.617021 (-3100 3810);
PAINT ORANGE (-3100 3810);
WIRE 16 -1 (-2325 3800)(-2325 3700);
WIRE 16 -1 (-1275 950)(-2000 950);
FORCEPROP 2 LAST SIG_NAME XDP_CPU_OBSFN_B1_MBP7_N
J 0
(-1910 960);
DISPLAY 0.617021 (-1910 960);
PAINT ORANGE (-1910 960);
WIRE 16 -1 (-1275 1550)(-2000 1550);
FORCEPROP 2 LAST SIG_NAME XDP_CPU_PREQ_N
J 0
(-1910 1560);
DISPLAY 0.617021 (-1910 1560);
PAINT ORANGE (-1910 1560);
WIRE 16 -1 (-1275 1350)(-2000 1350);
FORCEPROP 2 LAST SIG_NAME XDP_CPU_PRDY_N
J 0
(-1910 1360);
DISPLAY 0.617021 (-1910 1360);
PAINT ORANGE (-1910 1360);
WIRE 16 -1 (-1275 1150)(-2000 1150);
FORCEPROP 2 LAST SIG_NAME XDP_CPU_OBSFN_B0_MBP6_N
J 0
(-1910 1160);
DISPLAY 0.617021 (-1910 1160);
PAINT ORANGE (-1910 1160);
WIRE 16 273 (-725 3075)(-725 725);
WIRE 16 -1 (-1275 2775)(-2000 2775);
FORCEPROP 2 LAST SIG_NAME XDP_CPU_TDI
J 0
(-1910 2785);
DISPLAY 0.617021 (-1910 2785);
PAINT ORANGE (-1910 2785);
WIRE 16 -1 (-1275 2575)(-2000 2575);
FORCEPROP 2 LAST SIG_NAME XDP_CPU_TDO
J 0
(-1910 2585);
DISPLAY 0.617021 (-1910 2585);
PAINT ORANGE (-1910 2585);
WIRE 16 -1 (-1275 2375)(-2000 2375);
FORCEPROP 2 LAST SIG_NAME XDP_CPU_TMS
J 0
(-1910 2385);
DISPLAY 0.617021 (-1910 2385);
PAINT ORANGE (-1910 2385);
WIRE 16 -1 (-1275 2175)(-2000 2175);
FORCEPROP 2 LAST SIG_NAME XDP_CPU_TRST_N
J 0
(-1910 2185);
DISPLAY 0.617021 (-1910 2185);
PAINT ORANGE (-1910 2185);
WIRE 16 -1 (-1200 3950)(-3150 3950);
FORCEPROP 2 LAST SIG_NAME XDP_PRDY_N
J 0
(-3100 3960);
DISPLAY 0.617021 (-3100 3960);
PAINT ORANGE (-3100 3960);
WIRE 16 -1 (-1200 4325)(-1200 3950);
WIRE 16 -1 (-1575 4025)(-3150 4025);
FORCEPROP 2 LAST SIG_NAME XDP_PREQ_N
J 0
(-3100 4035);
DISPLAY 0.617021 (-3100 4035);
PAINT ORANGE (-3100 4035);
WIRE 16 -1 (-1575 4325)(-1575 4025);
WIRE 16 273 (-850 5150)(-850 3200);
WIRE 16 -1 (-2700 4250)(-3150 4250);
FORCEPROP 2 LAST SIG_NAME XDP_TMS
J 0
(-3100 4260);
DISPLAY 0.617021 (-3100 4260);
PAINT ORANGE (-3100 4260);
WIRE 16 -1 (-2700 4250)(-2700 4325);
WIRE 16 -1 (-2325 4175)(-3150 4175);
FORCEPROP 2 LAST SIG_NAME XDP_TDI
J 0
(-3100 4185);
DISPLAY 0.617021 (-3100 4185);
PAINT ORANGE (-3100 4185);
WIRE 16 -1 (-2325 4175)(-2325 4325);
WIRE 16 -1 (-1950 4100)(-3150 4100);
FORCEPROP 2 LAST SIG_NAME XDP_TDO
J 0
(-3100 4110);
DISPLAY 0.617021 (-3100 4110);
PAINT ORANGE (-3100 4110);
WIRE 16 -1 (-1950 4325)(-1950 4100);
WIRE 16 -1 (-725 4875)(-725 4625);
WIRE 16 -1 (925 4625)(-725 4625);
WIRE 16 -1 (925 4875)(-725 4875);
WIRE 16 -1 (925 4875)(925 4625);
WIRE 16 -1 (-175 3025)(-175 2775);
WIRE 16 -1 (1475 2775)(-175 2775);
WIRE 16 -1 (1475 3025)(-175 3025);
WIRE 16 -1 (1475 3025)(1475 2775);
WIRE 16 -1 (875 1425)(-50 1425);
FORCEPROP 2 LAST SIG_NAME XDP_CPU_TCK0
J 0
(-10 1435);
DISPLAY 0.617021 (-10 1435);
PAINT ORANGE (-10 1435);
WIRE 16 -1 (875 1200)(875 1425);
WIRE 16 -1 (1950 1950)(-50 1950);
FORCEPROP 2 LAST SIG_NAME XDP_CPU_PRDY_N
J 0
(-10 1960);
DISPLAY 0.617021 (-10 1960);
PAINT ORANGE (-10 1960);
WIRE 16 -1 (1950 2300)(1950 1950);
WIRE 16 -1 (1600 2025)(-50 2025);
FORCEPROP 2 LAST SIG_NAME XDP_CPU_PREQ_N
J 0
(-10 2035);
DISPLAY 0.617021 (-10 2035);
PAINT ORANGE (-10 2035);
WIRE 16 -1 (1600 2300)(1600 2025);
WIRE 16 -1 (500 2250)(-50 2250);
FORCEPROP 2 LAST SIG_NAME XDP_CPU_TMS
J 0
(-10 2260);
DISPLAY 0.617021 (-10 2260);
PAINT ORANGE (-10 2260);
WIRE 16 -1 (500 2250)(500 2300);
WIRE 16 -1 (875 2175)(-50 2175);
FORCEPROP 2 LAST SIG_NAME XDP_CPU1_TDI
J 0
(-10 2185);
DISPLAY 0.617021 (-10 2185);
PAINT ORANGE (-10 2185);
WIRE 16 -1 (875 2175)(875 2300);
WIRE 16 -1 (275 3650)(-250 3650);
FORCEPROP 2 LAST SIG_NAME XDP_CPU_TDI
J 0
(-225 3660);
DISPLAY 0.617021 (-225 3660);
PAINT ORANGE (-225 3660);
WIRE 16 -1 (275 3650)(275 3700);
WIRE 16 -1 (575 3575)(-250 3575);
FORCEPROP 2 LAST SIG_NAME XDP_CPU0_TDO
J 0
(-225 3585);
DISPLAY 0.617021 (-225 3585);
PAINT ORANGE (-225 3585);
WIRE 16 -1 (575 3700)(575 3575);
WIRE 16 -1 (875 3500)(-250 3500);
FORCEPROP 2 LAST SIG_NAME XDP_CPU_MBP0_N
J 0
(-225 3510);
DISPLAY 0.617021 (-225 3510);
PAINT ORANGE (-225 3510);
WIRE 16 -1 (875 3725)(875 3500);
WIRE 16 -1 (1225 2100)(-50 2100);
FORCEPROP 2 LAST SIG_NAME XDP_CPU1_TDO
J 0
(-10 2110);
DISPLAY 0.617021 (-10 2110);
PAINT ORANGE (-10 2110);
WIRE 16 -1 (1225 2300)(1225 2100);
WIRE 16 -1 (1175 3425)(-250 3425);
FORCEPROP 2 LAST SIG_NAME XDP_CPU_MBP1_N
J 0
(-225 3435);
DISPLAY 0.617021 (-225 3435);
PAINT ORANGE (-225 3435);
WIRE 16 -1 (1175 3700)(1175 3425);
WIRE 16 682 (425 900)(425 1300);
WIRE 16 682 (2375 900)(425 900);
WIRE 16 682 (425 1300)(2375 1300);
WIRE 16 682 (2375 1300)(2375 900);
WIRE 16 -1 (2325 1875)(-50 1875);
FORCEPROP 2 LAST SIG_NAME XDP_CPU_MBP0_N
J 0
(-10 1885);
DISPLAY 0.617021 (-10 1885);
PAINT ORANGE (-10 1885);
WIRE 16 -1 (2325 2300)(2325 1875);
WIRE 16 -1 (2675 1800)(-50 1800);
FORCEPROP 2 LAST SIG_NAME XDP_CPU_MBP1_N
J 0
(-10 1810);
DISPLAY 0.617021 (-10 1810);
PAINT ORANGE (-10 1810);
WIRE 16 -1 (2675 2300)(2675 1800);
WIRE 16 -1 (-50 1575)(3175 1575);
FORCEPROP 2 LAST SIG_NAME XDP_CPU_OBSFN_B0_MBP6_N
J 0
(-10 1585);
DISPLAY 0.617021 (-10 1585);
PAINT ORANGE (-10 1585);
WIRE 16 -1 (3175 2300)(3175 1575);
WIRE 16 -1 (2825 3425)(2200 3425);
FORCEPROP 2 LAST SIG_NAME XDP_CPU0_TDO
J 0
(2190 3435);
DISPLAY 0.617021 (2190 3435);
PAINT ORANGE (2190 3435);
WIRE 16 -1 (2825 3375)(2200 3375);
FORCEPROP 2 LAST SIG_NAME FM_CPU1_SKTOCC_LVT3_N
J 0
(2190 3385);
DISPLAY 0.617021 (2190 3385);
PAINT ORANGE (2190 3385);
WIRE 16 -1 (3325 3425)(3725 3425);
FORCEPROP 2 LAST SIG_NAME XDP_CPU1_TDI
J 0
(3390 3435);
DISPLAY 0.617021 (3390 3435);
PAINT ORANGE (3390 3435);
WIRE 16 273 (1550 4400)(1550 3300);
WIRE 16 273 (1550 4400)(1075 4400);
WIRE 16 273 (1075 4400)(1075 5150);
WIRE 16 -1 (1825 4675)(2250 4675);
FORCEPROP 2 LAST SIG_NAME XDP_CPU_TDO
J 0
(1815 4685);
DISPLAY 0.617021 (1815 4685);
PAINT ORANGE (1815 4685);
WIRE 16 -1 (2950 4725)(3600 4725);
FORCEPROP 2 LAST SIG_NAME XDP_CPU1_TDO
J 0
(3025 4735);
DISPLAY 0.617021 (3025 4735);
PAINT ORANGE (3025 4735);
WIRE 16 -1 (2950 4625)(3600 4625);
FORCEPROP 2 LAST SIG_NAME XDP_CPU0_TDO
J 0
(3025 4635);
DISPLAY 0.617021 (3025 4635);
PAINT ORANGE (3025 4635);
WIRE 16 -1 (3600 4825)(2950 4825);
FORCEPROP 2 LAST SIG_NAME FM_CPU1_SKTOCC_LVT3_N
J 0
(3025 4835);
DISPLAY 0.617021 (3025 4835);
PAINT ORANGE (3025 4835);
WIRE 16 -1 (-700 4850)(-700 4650);
WIRE 16 -1 (-700 4650)(900 4650);
WIRE 16 -1 (900 4850)(-700 4850);
WIRE 16 -1 (900 4850)(900 4650);
DOT 1 (3100 4200);
DOT 1 (3500 2600);
DOT 1 (-2500 1450);
DOT 1 (2700 4200);
DOT 1 (875 4025);
DOT 1 (2700 3750);
DOT 1 (500 850);
DOT 1 (-1575 4650);
DOT 1 (-1950 4650);
DOT 1 (-2325 4650);
DOT 1 (-2500 2475);
DOT 1 (-2500 1250);
DOT 1 (-2500 850);
DOT 1 (-2500 1050);
DOT 1 (1175 4025);
DOT 1 (-2700 3400);
DOT 1 (-2325 3400);
DOT 1 (-2500 2075);
DOT 1 (2675 2625);
DOT 1 (-1200 4650);
DOT 1 (575 4025);
DOT 1 (1225 2575);
DOT 1 (1950 2625);
DOT 1 (-2500 2275);
FORCENOTE
74CBTLVG125 VCC PIN
(3675 3700) 0;
DISPLAY LEFT (3675 3700);
DISPLAY 0.808511 (3675 3700);
PAINT PURPLE (3675 3700);
FORCENOTE
ROOM=DEBUG
(-3651 361) 0;
DISPLAY LEFT (-3651 361);
PAINT PURPLE (-3651 361);
FORCENOTE
PCH XDP TERMINATIONS
(-3350 4975) 0;
DISPLAY LEFT (-3350 4975);
DISPLAY 1.170213 (-3350 4975);
PAINT PURPLE (-3350 4975);
FORCENOTE
CPU0 XDP TERMINATIONS
(-475 4725) 0;
DISPLAY LEFT (-475 4725);
DISPLAY 1.170213 (-475 4725);
PAINT PURPLE (-475 4725);
FORCENOTE
CPU1 XDP TERMINATIONS
(75 2875) 0;
DISPLAY LEFT (75 2875);
DISPLAY 1.170213 (75 2875);
PAINT PURPLE (75 2875);
FORCENOTE
PLACE NEAR 
(3675 3750) 0;
DISPLAY LEFT (3675 3750);
DISPLAY 0.808511 (3675 3750);
PAINT PURPLE (3675 3750);
QUIT
